FILE_TYPE = MACRO_DRAWING;
SET COLOR_WIRE YELLOW;
SET COLOR_PROP ORANGE;
SET COLOR_DOT WHITE;
SET COLOR_ARC YELLOW;
SET COLOR_BODY GREEN;
SET COLOR_NOTE PURPLE;
SET PROP_DISPLAY VALUE;
SET PAGE_NUMBER P288;
FORCEADD TP_TDR_4P_FTS..1
R 4
(4725 1150);
FORCEPROP 1 LAST PART_NUMBER TP15
J 0
(4600 1490);
DISPLAY 0.723404 (4600 1490);
PAINT GREEN (4600 1490);
DISPLAY INVISIBLE (4600 1490);
FORCEPROP 2 LAST VALUE TP_TDR_4P_DIP
J 0
(4600 1350);
DISPLAY 1.021277 (4600 1350);
FORCEPROP 2 LAST PACK_TYPE TH
J 0
(4600 1400);
DISPLAY 1.021277 (4600 1400);
FORCEPROP 1 LAST MATERIAL EMPTY
J 0
(4600 1540);
DISPLAY 0.723404 (4600 1540);
PAINT GREEN (4600 1540);
FORCEPROP 1 LAST $LOCATION X23
J 0
(4600 1445);
DISPLAY 0.723404 (4600 1445);
PAINT GREEN (4600 1445);
FORCEPROP 0 LASTPIN (5000 1075) $PN 2
J 0
(5010 1085);
DISPLAY 0.680851 (5010 1085);
PAINT MONO (5010 1085);
FORCEPROP 0 LASTPIN (5000 1225) $PN 3
J 0
(5010 1235);
DISPLAY 0.680851 (5010 1235);
PAINT MONO (5010 1235);
FORCEPROP 0 LASTPIN (4450 1075) $PN 1
J 2
(4440 1085);
DISPLAY 0.680851 (4440 1085);
PAINT MONO (4440 1085);
FORCEPROP 0 LASTPIN (4450 1225) $PN 4
J 2
(4440 1235);
DISPLAY 0.680851 (4440 1235);
PAINT MONO (4440 1235);
FORCEPROP 1 LAST PATH I10
R 2
J 0
(4625 970);
DISPLAY 0.723404 (4625 970);
PAINT GREEN (4625 970);
DISPLAY INVISIBLE (4625 970);
FORCEPROP 1 LAST NEEDS_NO_SIZE TRUE
R 2
J 0
(4725 1150);
DISPLAY 0.468085 (4725 1150);
PAINT GREEN (4725 1150);
DISPLAY INVISIBLE (4725 1150);
FORCEPROP 2 LAST CDS_LIB pure_quanta
R 2
J 0
(4725 1150);
DISPLAY INVISIBLE (4725 1150);
FORCEPROP 0 LAST CDS_LOCATION X23
J 0
(4600 1575);
DISPLAY 1.021277 (4600 1575);
DISPLAY INVISIBLE (4600 1575);
FORCEPROP 0 LAST $SEC 1
J 0
(4600 1575);
DISPLAY 0.680851 (4600 1575);
PAINT MONO (4600 1575);
DISPLAY INVISIBLE (4600 1575);
FORCEPROP 0 LAST CDS_SEC 1
J 0
(4600 1575);
DISPLAY 1.021277 (4600 1575);
DISPLAY INVISIBLE (4600 1575);
FORCEADD UNIVERSAL_GND..1
(-1525 900);
FORCEPROP 3 LASTPIN (-1525 950) SIG_NAME T1_GND\g
J 0
(-1515 960);
DISPLAY 0.659574 (-1515 960);
PAINT MONO (-1515 960);
DISPLAY INVISIBLE (-1515 960);
FORCEPROP 1 LAST HDL_POWER T1_GND
J 1
(-1500 825);
DISPLAY 0.872340 (-1500 825);
PAINT GREEN (-1500 825);
FORCEPROP 1 LAST PATH I100
J 0
(-1450 900);
DISPLAY 0.872340 (-1450 900);
PAINT AQUA (-1450 900);
DISPLAY INVISIBLE (-1450 900);
FORCEPROP 2 LAST CDS_LIB logical_power
J 0
(-1525 900);
DISPLAY INVISIBLE (-1525 900);
FORCEADD TDR_3P..2
(-2875 1650);
FORCEPROP 1 LAST PART_NUMBER N_A
J 1
(-2815 1500);
DISPLAY 0.872340 (-2815 1500);
PAINT PINK (-2815 1500);
DISPLAY INVISIBLE (-2815 1500);
FORCEPROP 1 LAST PACK_TYPE TH2
J 2
(-2850 1800);
DISPLAY 0.872340 (-2850 1800);
FORCEPROP 1 LAST $LOCATION DB13
J 2
(-2850 1850);
DISPLAY 0.872340 (-2850 1850);
PAINT PINK (-2850 1850);
FORCEPROP 0 LASTPIN (-3075 1650) $PN 1
J 2
(-3085 1660);
DISPLAY 0.680851 (-3085 1660);
PAINT MONO (-3085 1660);
FORCEPROP 0 LASTPIN (-2775 1700) $PN 2
J 0
(-2765 1710);
DISPLAY 0.680851 (-2765 1710);
PAINT MONO (-2765 1710);
FORCEPROP 0 LASTPIN (-2775 1600) $PN 3
J 0
(-2765 1610);
DISPLAY 0.680851 (-2765 1610);
PAINT MONO (-2765 1610);
FORCEPROP 1 LAST PATH I101
J 2
(-2575 1800);
DISPLAY 0.872340 (-2575 1800);
PAINT PINK (-2575 1800);
DISPLAY INVISIBLE (-2575 1800);
FORCEPROP 1 LAST MATERIAL EMPTY
J 2
(-2875 1800);
DISPLAY 0.872340 (-2875 1800);
PAINT PINK (-2875 1800);
DISPLAY INVISIBLE (-2875 1800);
FORCEPROP 2 LAST CDS_LIB pure_quanta
J 0
(-2875 1650);
DISPLAY INVISIBLE (-2875 1650);
FORCEPROP 1 LAST CDS_LMAN_SYM_OUTLINE -150,100,50,-100
J 0
(-2875 1650);
DISPLAY 0.468085 (-2875 1650);
PAINT GREEN (-2875 1650);
DISPLAY INVISIBLE (-2875 1650);
FORCEPROP 0 LAST CDS_LOCATION DB13
J 0
(-2850 1900);
DISPLAY 1.021277 (-2850 1900);
DISPLAY INVISIBLE (-2850 1900);
FORCEPROP 0 LAST $SEC 1
J 0
(-2850 1900);
DISPLAY 0.680851 (-2850 1900);
PAINT MONO (-2850 1900);
DISPLAY INVISIBLE (-2850 1900);
FORCEPROP 0 LAST CDS_SEC 1
J 0
(-2850 1900);
DISPLAY 1.021277 (-2850 1900);
DISPLAY INVISIBLE (-2850 1900);
FORCEADD UNIVERSAL_GND..1
(-3225 1425);
FORCEPROP 3 LASTPIN (-3225 1475) SIG_NAME T1_GND\g
J 0
(-3215 1485);
DISPLAY 0.659574 (-3215 1485);
PAINT MONO (-3215 1485);
DISPLAY INVISIBLE (-3215 1485);
FORCEPROP 1 LAST HDL_POWER T1_GND
J 1
(-3200 1350);
DISPLAY 0.872340 (-3200 1350);
PAINT GREEN (-3200 1350);
FORCEPROP 1 LAST PATH I102
J 0
(-3150 1425);
DISPLAY 0.872340 (-3150 1425);
PAINT AQUA (-3150 1425);
DISPLAY INVISIBLE (-3150 1425);
FORCEPROP 2 LAST CDS_LIB logical_power
J 0
(-3225 1425);
DISPLAY INVISIBLE (-3225 1425);
FORCEADD UNIVERSAL_GND..1
(-3225 900);
FORCEPROP 3 LASTPIN (-3225 950) SIG_NAME T1_GND\g
J 0
(-3215 960);
DISPLAY 0.659574 (-3215 960);
PAINT MONO (-3215 960);
DISPLAY INVISIBLE (-3215 960);
FORCEPROP 1 LAST HDL_POWER T1_GND
J 1
(-3200 825);
DISPLAY 0.872340 (-3200 825);
PAINT GREEN (-3200 825);
FORCEPROP 1 LAST PATH I103
J 0
(-3150 900);
DISPLAY 0.872340 (-3150 900);
PAINT AQUA (-3150 900);
DISPLAY INVISIBLE (-3150 900);
FORCEPROP 2 LAST CDS_LIB logical_power
J 0
(-3225 900);
DISPLAY INVISIBLE (-3225 900);
FORCEADD UNIVERSAL_GND..1
(2425 250);
FORCEPROP 3 LASTPIN (2425 300) SIG_NAME T1_GND\g
J 0
(2435 310);
DISPLAY 0.659574 (2435 310);
PAINT MONO (2435 310);
DISPLAY INVISIBLE (2435 310);
FORCEPROP 1 LAST HDL_POWER T1_GND
J 1
(2450 175);
DISPLAY 0.872340 (2450 175);
PAINT GREEN (2450 175);
FORCEPROP 2 LAST CDS_LIB logical_power
J 0
(2425 250);
DISPLAY INVISIBLE (2425 250);
FORCEPROP 1 LAST PATH I104
J 0
(2500 250);
DISPLAY 0.872340 (2500 250);
PAINT AQUA (2500 250);
DISPLAY INVISIBLE (2500 250);
FORCEADD UNIVERSAL_GND..1
(2425 -525);
FORCEPROP 3 LASTPIN (2425 -475) SIG_NAME T1_GND\g
J 0
(2435 -465);
DISPLAY 0.659574 (2435 -465);
PAINT MONO (2435 -465);
DISPLAY INVISIBLE (2435 -465);
FORCEPROP 1 LAST HDL_POWER T1_GND
J 1
(2450 -600);
DISPLAY 0.872340 (2450 -600);
PAINT GREEN (2450 -600);
FORCEPROP 2 LAST CDS_LIB logical_power
J 0
(2425 -525);
DISPLAY INVISIBLE (2425 -525);
FORCEPROP 1 LAST PATH I105
J 0
(2500 -525);
DISPLAY 0.872340 (2500 -525);
PAINT AQUA (2500 -525);
DISPLAY INVISIBLE (2500 -525);
FORCEADD TP_TDR_4P_FTS..1
R 4
(2025 475);
FORCEPROP 1 LAST PART_NUMBER TP15
J 0
(1900 815);
DISPLAY 0.723404 (1900 815);
PAINT GREEN (1900 815);
DISPLAY INVISIBLE (1900 815);
FORCEPROP 2 LAST PACK_TYPE TH
J 0
(1900 725);
DISPLAY 1.021277 (1900 725);
FORCEPROP 1 LAST MATERIAL EMPTY
J 0
(1900 865);
DISPLAY 0.723404 (1900 865);
PAINT GREEN (1900 865);
FORCEPROP 2 LAST VALUE TP_TDR_4P_DIP
J 0
(1900 675);
DISPLAY 1.021277 (1900 675);
FORCEPROP 1 LAST $LOCATION X27
J 0
(1900 770);
DISPLAY 0.723404 (1900 770);
PAINT GREEN (1900 770);
FORCEPROP 0 LASTPIN (2300 400) $PN 2
J 0
(2310 410);
DISPLAY 0.680851 (2310 410);
PAINT MONO (2310 410);
FORCEPROP 0 LASTPIN (2300 550) $PN 3
J 0
(2310 560);
DISPLAY 0.680851 (2310 560);
PAINT MONO (2310 560);
FORCEPROP 0 LASTPIN (1750 400) $PN 1
J 2
(1740 410);
DISPLAY 0.680851 (1740 410);
PAINT MONO (1740 410);
FORCEPROP 0 LASTPIN (1750 550) $PN 4
J 2
(1740 560);
DISPLAY 0.680851 (1740 560);
PAINT MONO (1740 560);
FORCEPROP 1 LAST NEEDS_NO_SIZE TRUE
R 2
J 0
(2025 475);
DISPLAY 0.468085 (2025 475);
PAINT GREEN (2025 475);
DISPLAY INVISIBLE (2025 475);
FORCEPROP 2 LAST CDS_LIB pure_quanta
R 2
J 0
(2025 475);
DISPLAY INVISIBLE (2025 475);
FORCEPROP 1 LAST PATH I106
R 2
J 0
(1925 295);
DISPLAY 0.723404 (1925 295);
PAINT GREEN (1925 295);
DISPLAY INVISIBLE (1925 295);
FORCEPROP 0 LAST CDS_LOCATION X27
J 0
(1900 900);
DISPLAY 1.021277 (1900 900);
DISPLAY INVISIBLE (1900 900);
FORCEPROP 0 LAST $SEC 1
J 0
(1900 900);
DISPLAY 0.680851 (1900 900);
PAINT MONO (1900 900);
DISPLAY INVISIBLE (1900 900);
FORCEPROP 0 LAST CDS_SEC 1
J 0
(1900 900);
DISPLAY 1.021277 (1900 900);
DISPLAY INVISIBLE (1900 900);
FORCEADD TP_TDR_4P_FTS..1
R 4
(2025 -300);
FORCEPROP 1 LAST PART_NUMBER TP15
J 0
(1900 40);
DISPLAY 0.723404 (1900 40);
PAINT GREEN (1900 40);
DISPLAY INVISIBLE (1900 40);
FORCEPROP 2 LAST VALUE TP_TDR_4P_DIP
J 0
(1900 -100);
DISPLAY 1.021277 (1900 -100);
FORCEPROP 1 LAST MATERIAL EMPTY
J 0
(1900 90);
DISPLAY 0.723404 (1900 90);
PAINT GREEN (1900 90);
FORCEPROP 2 LAST PACK_TYPE TH
J 0
(1900 -50);
DISPLAY 1.021277 (1900 -50);
FORCEPROP 1 LAST $LOCATION X28
J 0
(1900 -5);
DISPLAY 0.723404 (1900 -5);
PAINT GREEN (1900 -5);
FORCEPROP 0 LASTPIN (2300 -375) $PN 2
J 0
(2310 -365);
DISPLAY 0.680851 (2310 -365);
PAINT MONO (2310 -365);
FORCEPROP 0 LASTPIN (2300 -225) $PN 3
J 0
(2310 -215);
DISPLAY 0.680851 (2310 -215);
PAINT MONO (2310 -215);
FORCEPROP 0 LASTPIN (1750 -375) $PN 1
J 2
(1740 -365);
DISPLAY 0.680851 (1740 -365);
PAINT MONO (1740 -365);
FORCEPROP 0 LASTPIN (1750 -225) $PN 4
J 2
(1740 -215);
DISPLAY 0.680851 (1740 -215);
PAINT MONO (1740 -215);
FORCEPROP 1 LAST NEEDS_NO_SIZE TRUE
R 2
J 0
(2025 -300);
DISPLAY 0.468085 (2025 -300);
PAINT GREEN (2025 -300);
DISPLAY INVISIBLE (2025 -300);
FORCEPROP 2 LAST CDS_LIB pure_quanta
R 2
J 0
(2025 -300);
DISPLAY INVISIBLE (2025 -300);
FORCEPROP 1 LAST PATH I107
R 2
J 0
(1925 -480);
DISPLAY 0.723404 (1925 -480);
PAINT GREEN (1925 -480);
DISPLAY INVISIBLE (1925 -480);
FORCEPROP 0 LAST CDS_LOCATION X28
J 0
(1900 125);
DISPLAY 1.021277 (1900 125);
DISPLAY INVISIBLE (1900 125);
FORCEPROP 0 LAST $SEC 1
J 0
(1900 125);
DISPLAY 0.680851 (1900 125);
PAINT MONO (1900 125);
DISPLAY INVISIBLE (1900 125);
FORCEPROP 0 LAST CDS_SEC 1
J 0
(1900 125);
DISPLAY 1.021277 (1900 125);
DISPLAY INVISIBLE (1900 125);
FORCEADD TP_TDR_4P_FTS..1
(700 475);
FORCEPROP 1 LAST PART_NUMBER TP15
J 0
(575 710);
DISPLAY 0.723404 (575 710);
PAINT GREEN (575 710);
DISPLAY INVISIBLE (575 710);
FORCEPROP 2 LAST VALUE TP_TDR_4P_DIP
J 0
(575 850);
DISPLAY 1.021277 (575 850);
FORCEPROP 2 LAST PACK_TYPE TH
J 0
(575 800);
DISPLAY 1.021277 (575 800);
FORCEPROP 1 LAST MATERIAL EMPTY
J 0
(575 660);
DISPLAY 0.723404 (575 660);
PAINT GREEN (575 660);
FORCEPROP 1 LAST $LOCATION X25
J 0
(575 755);
DISPLAY 0.723404 (575 755);
PAINT GREEN (575 755);
FORCEPROP 0 LASTPIN (425 550) $PN 2
J 2
(415 560);
DISPLAY 0.680851 (415 560);
PAINT MONO (415 560);
FORCEPROP 0 LASTPIN (425 400) $PN 3
J 2
(415 410);
DISPLAY 0.680851 (415 410);
PAINT MONO (415 410);
FORCEPROP 0 LASTPIN (975 550) $PN 1
J 0
(985 560);
DISPLAY 0.680851 (985 560);
PAINT MONO (985 560);
FORCEPROP 0 LASTPIN (975 400) $PN 4
J 0
(985 410);
DISPLAY 0.680851 (985 410);
PAINT MONO (985 410);
FORCEPROP 1 LAST NEEDS_NO_SIZE TRUE
J 0
(700 475);
DISPLAY 0.468085 (700 475);
PAINT GREEN (700 475);
DISPLAY INVISIBLE (700 475);
FORCEPROP 2 LAST CDS_LIB pure_quanta
J 0
(700 475);
DISPLAY INVISIBLE (700 475);
FORCEPROP 1 LAST PATH I108
J 0
(800 655);
DISPLAY 0.723404 (800 655);
PAINT GREEN (800 655);
DISPLAY INVISIBLE (800 655);
FORCEPROP 0 LAST CDS_LOCATION X25
J 0
(575 900);
DISPLAY 1.021277 (575 900);
DISPLAY INVISIBLE (575 900);
FORCEPROP 0 LAST $SEC 1
J 0
(575 900);
DISPLAY 0.680851 (575 900);
PAINT MONO (575 900);
DISPLAY INVISIBLE (575 900);
FORCEPROP 0 LAST CDS_SEC 1
J 0
(575 900);
DISPLAY 1.021277 (575 900);
DISPLAY INVISIBLE (575 900);
FORCEADD UNIVERSAL_GND..1
(275 250);
FORCEPROP 3 LASTPIN (275 300) SIG_NAME T1_GND\g
J 0
(285 310);
DISPLAY 0.659574 (285 310);
PAINT MONO (285 310);
DISPLAY INVISIBLE (285 310);
FORCEPROP 1 LAST HDL_POWER T1_GND
J 1
(300 175);
DISPLAY 0.872340 (300 175);
PAINT GREEN (300 175);
FORCEPROP 2 LAST CDS_LIB logical_power
J 0
(275 250);
DISPLAY INVISIBLE (275 250);
FORCEPROP 1 LAST PATH I109
J 0
(350 250);
DISPLAY 0.872340 (350 250);
PAINT AQUA (350 250);
DISPLAY INVISIBLE (350 250);
FORCEADD TP_TDR_4P_FTS..1
(3400 4250);
FORCEPROP 1 LAST PART_NUMBER TP15
J 0
(3275 4485);
DISPLAY 0.723404 (3275 4485);
PAINT GREEN (3275 4485);
DISPLAY INVISIBLE (3275 4485);
FORCEPROP 2 LAST PACK_TYPE TH
J 0
(3275 4575);
DISPLAY 1.021277 (3275 4575);
FORCEPROP 1 LAST MATERIAL EMPTY
J 0
(3275 4435);
DISPLAY 0.723404 (3275 4435);
PAINT GREEN (3275 4435);
FORCEPROP 2 LAST VALUE TP_TDR_4P_DIP
J 0
(3275 4625);
DISPLAY 1.021277 (3275 4625);
FORCEPROP 1 LAST $LOCATION X13
J 0
(3275 4530);
DISPLAY 0.723404 (3275 4530);
PAINT GREEN (3275 4530);
FORCEPROP 0 LASTPIN (3125 4325) $PN 2
J 2
(3115 4335);
DISPLAY 0.680851 (3115 4335);
PAINT MONO (3115 4335);
FORCEPROP 0 LASTPIN (3125 4175) $PN 3
J 2
(3115 4185);
DISPLAY 0.680851 (3115 4185);
PAINT MONO (3115 4185);
FORCEPROP 0 LASTPIN (3675 4325) $PN 1
J 0
(3685 4335);
DISPLAY 0.680851 (3685 4335);
PAINT MONO (3685 4335);
FORCEPROP 0 LASTPIN (3675 4175) $PN 4
J 0
(3685 4185);
DISPLAY 0.680851 (3685 4185);
PAINT MONO (3685 4185);
FORCEPROP 1 LAST NEEDS_NO_SIZE TRUE
J 0
(3400 4250);
DISPLAY 0.468085 (3400 4250);
PAINT GREEN (3400 4250);
DISPLAY INVISIBLE (3400 4250);
FORCEPROP 2 LAST CDS_LIB pure_quanta
J 0
(3400 4250);
DISPLAY INVISIBLE (3400 4250);
FORCEPROP 1 LAST PATH I11
J 0
(3500 4430);
DISPLAY 0.723404 (3500 4430);
PAINT GREEN (3500 4430);
DISPLAY INVISIBLE (3500 4430);
FORCEPROP 0 LAST CDS_LOCATION X13
J 0
(3275 4675);
DISPLAY 1.021277 (3275 4675);
DISPLAY INVISIBLE (3275 4675);
FORCEPROP 0 LAST $SEC 1
J 0
(3275 4675);
DISPLAY 0.680851 (3275 4675);
PAINT MONO (3275 4675);
DISPLAY INVISIBLE (3275 4675);
FORCEPROP 0 LAST CDS_SEC 1
J 0
(3275 4675);
DISPLAY 1.021277 (3275 4675);
DISPLAY INVISIBLE (3275 4675);
FORCEADD TP_TDR_4P_FTS..1
(700 -300);
FORCEPROP 1 LAST PART_NUMBER TP15
J 0
(575 -65);
DISPLAY 0.723404 (575 -65);
PAINT GREEN (575 -65);
DISPLAY INVISIBLE (575 -65);
FORCEPROP 1 LAST MATERIAL EMPTY
J 0
(575 -115);
DISPLAY 0.723404 (575 -115);
PAINT GREEN (575 -115);
FORCEPROP 2 LAST PACK_TYPE TH
J 0
(575 25);
DISPLAY 1.021277 (575 25);
FORCEPROP 2 LAST VALUE TP_TDR_4P_DIP
J 0
(575 75);
DISPLAY 1.021277 (575 75);
FORCEPROP 1 LAST $LOCATION X26
J 0
(575 -20);
DISPLAY 0.723404 (575 -20);
PAINT GREEN (575 -20);
FORCEPROP 0 LASTPIN (425 -225) $PN 2
J 2
(415 -215);
DISPLAY 0.680851 (415 -215);
PAINT MONO (415 -215);
FORCEPROP 0 LASTPIN (425 -375) $PN 3
J 2
(415 -365);
DISPLAY 0.680851 (415 -365);
PAINT MONO (415 -365);
FORCEPROP 0 LASTPIN (975 -225) $PN 1
J 0
(985 -215);
DISPLAY 0.680851 (985 -215);
PAINT MONO (985 -215);
FORCEPROP 0 LASTPIN (975 -375) $PN 4
J 0
(985 -365);
DISPLAY 0.680851 (985 -365);
PAINT MONO (985 -365);
FORCEPROP 1 LAST NEEDS_NO_SIZE TRUE
J 0
(700 -300);
DISPLAY 0.468085 (700 -300);
PAINT GREEN (700 -300);
DISPLAY INVISIBLE (700 -300);
FORCEPROP 2 LAST CDS_LIB pure_quanta
J 0
(700 -300);
DISPLAY INVISIBLE (700 -300);
FORCEPROP 1 LAST PATH I110
J 0
(800 -120);
DISPLAY 0.723404 (800 -120);
PAINT GREEN (800 -120);
DISPLAY INVISIBLE (800 -120);
FORCEPROP 0 LAST CDS_LOCATION X26
J 0
(575 125);
DISPLAY 1.021277 (575 125);
DISPLAY INVISIBLE (575 125);
FORCEPROP 0 LAST $SEC 1
J 0
(575 125);
DISPLAY 0.680851 (575 125);
PAINT MONO (575 125);
DISPLAY INVISIBLE (575 125);
FORCEPROP 0 LAST CDS_SEC 1
J 0
(575 125);
DISPLAY 1.021277 (575 125);
DISPLAY INVISIBLE (575 125);
FORCEADD UNIVERSAL_GND..1
(275 -525);
FORCEPROP 3 LASTPIN (275 -475) SIG_NAME T1_GND\g
J 0
(285 -465);
DISPLAY 0.659574 (285 -465);
PAINT MONO (285 -465);
DISPLAY INVISIBLE (285 -465);
FORCEPROP 1 LAST HDL_POWER T1_GND
J 1
(300 -600);
DISPLAY 0.872340 (300 -600);
PAINT GREEN (300 -600);
FORCEPROP 2 LAST CDS_LIB logical_power
J 0
(275 -525);
DISPLAY INVISIBLE (275 -525);
FORCEPROP 1 LAST PATH I111
J 0
(350 -525);
DISPLAY 0.872340 (350 -525);
PAINT AQUA (350 -525);
DISPLAY INVISIBLE (350 -525);
FORCEADD TP_TDR_4P_FTS..1
R 4
(4700 475);
FORCEPROP 1 LAST PART_NUMBER TP15
J 0
(4575 815);
DISPLAY 0.723404 (4575 815);
PAINT GREEN (4575 815);
DISPLAY INVISIBLE (4575 815);
FORCEPROP 1 LAST MATERIAL EMPTY
J 0
(4575 865);
DISPLAY 0.723404 (4575 865);
PAINT GREEN (4575 865);
FORCEPROP 2 LAST PACK_TYPE TH
J 0
(4575 725);
DISPLAY 1.021277 (4575 725);
FORCEPROP 2 LAST VALUE TP_TDR_4P_DIP
J 0
(4575 675);
DISPLAY 1.021277 (4575 675);
FORCEPROP 1 LAST $LOCATION X31
J 0
(4575 770);
DISPLAY 0.723404 (4575 770);
PAINT GREEN (4575 770);
FORCEPROP 0 LASTPIN (4975 400) $PN 2
J 0
(4985 410);
DISPLAY 0.680851 (4985 410);
PAINT MONO (4985 410);
FORCEPROP 0 LASTPIN (4975 550) $PN 3
J 0
(4985 560);
DISPLAY 0.680851 (4985 560);
PAINT MONO (4985 560);
FORCEPROP 0 LASTPIN (4425 400) $PN 1
J 2
(4415 410);
DISPLAY 0.680851 (4415 410);
PAINT MONO (4415 410);
FORCEPROP 0 LASTPIN (4425 550) $PN 4
J 2
(4415 560);
DISPLAY 0.680851 (4415 560);
PAINT MONO (4415 560);
FORCEPROP 2 LAST CDS_LIB pure_quanta
R 2
J 0
(4700 475);
DISPLAY INVISIBLE (4700 475);
FORCEPROP 1 LAST NEEDS_NO_SIZE TRUE
R 2
J 0
(4700 475);
DISPLAY 0.468085 (4700 475);
PAINT GREEN (4700 475);
DISPLAY INVISIBLE (4700 475);
FORCEPROP 1 LAST PATH I112
R 2
J 0
(4600 295);
DISPLAY 0.723404 (4600 295);
PAINT GREEN (4600 295);
DISPLAY INVISIBLE (4600 295);
FORCEPROP 0 LAST CDS_LOCATION X31
J 0
(4575 900);
DISPLAY 1.021277 (4575 900);
DISPLAY INVISIBLE (4575 900);
FORCEPROP 0 LAST $SEC 1
J 0
(4575 900);
DISPLAY 0.680851 (4575 900);
PAINT MONO (4575 900);
DISPLAY INVISIBLE (4575 900);
FORCEPROP 0 LAST CDS_SEC 1
J 0
(4575 900);
DISPLAY 1.021277 (4575 900);
DISPLAY INVISIBLE (4575 900);
FORCEADD UNIVERSAL_GND..1
(5100 250);
FORCEPROP 3 LASTPIN (5100 300) SIG_NAME T1_GND\g
J 0
(5110 310);
DISPLAY 0.659574 (5110 310);
PAINT MONO (5110 310);
DISPLAY INVISIBLE (5110 310);
FORCEPROP 1 LAST HDL_POWER T1_GND
J 1
(5125 175);
DISPLAY 0.872340 (5125 175);
PAINT GREEN (5125 175);
FORCEPROP 2 LAST CDS_LIB logical_power
J 0
(5100 250);
DISPLAY INVISIBLE (5100 250);
FORCEPROP 1 LAST PATH I113
J 0
(5175 250);
DISPLAY 0.872340 (5175 250);
PAINT AQUA (5175 250);
DISPLAY INVISIBLE (5175 250);
FORCEADD UNIVERSAL_GND..1
(5100 -525);
FORCEPROP 3 LASTPIN (5100 -475) SIG_NAME T1_GND\g
J 0
(5110 -465);
DISPLAY 0.659574 (5110 -465);
PAINT MONO (5110 -465);
DISPLAY INVISIBLE (5110 -465);
FORCEPROP 1 LAST HDL_POWER T1_GND
J 1
(5125 -600);
DISPLAY 0.872340 (5125 -600);
PAINT GREEN (5125 -600);
FORCEPROP 2 LAST CDS_LIB logical_power
J 0
(5100 -525);
DISPLAY INVISIBLE (5100 -525);
FORCEPROP 1 LAST PATH I114
J 0
(5175 -525);
DISPLAY 0.872340 (5175 -525);
PAINT AQUA (5175 -525);
DISPLAY INVISIBLE (5175 -525);
FORCEADD TP_TDR_4P_FTS..1
R 4
(4700 -300);
FORCEPROP 1 LAST PART_NUMBER TP15
J 0
(4575 40);
DISPLAY 0.723404 (4575 40);
PAINT GREEN (4575 40);
DISPLAY INVISIBLE (4575 40);
FORCEPROP 1 LAST MATERIAL EMPTY
J 0
(4575 90);
DISPLAY 0.723404 (4575 90);
PAINT GREEN (4575 90);
FORCEPROP 2 LAST PACK_TYPE TH
J 0
(4575 -50);
DISPLAY 1.021277 (4575 -50);
FORCEPROP 2 LAST VALUE TP_TDR_4P_DIP
J 0
(4575 -100);
DISPLAY 1.021277 (4575 -100);
FORCEPROP 1 LAST $LOCATION X32
J 0
(4575 -5);
DISPLAY 0.723404 (4575 -5);
PAINT GREEN (4575 -5);
FORCEPROP 0 LASTPIN (4975 -375) $PN 2
J 0
(4985 -365);
DISPLAY 0.680851 (4985 -365);
PAINT MONO (4985 -365);
FORCEPROP 0 LASTPIN (4975 -225) $PN 3
J 0
(4985 -215);
DISPLAY 0.680851 (4985 -215);
PAINT MONO (4985 -215);
FORCEPROP 0 LASTPIN (4425 -375) $PN 1
J 2
(4415 -365);
DISPLAY 0.680851 (4415 -365);
PAINT MONO (4415 -365);
FORCEPROP 0 LASTPIN (4425 -225) $PN 4
J 2
(4415 -215);
DISPLAY 0.680851 (4415 -215);
PAINT MONO (4415 -215);
FORCEPROP 2 LAST CDS_LIB pure_quanta
R 2
J 0
(4700 -300);
DISPLAY INVISIBLE (4700 -300);
FORCEPROP 1 LAST NEEDS_NO_SIZE TRUE
R 2
J 0
(4700 -300);
DISPLAY 0.468085 (4700 -300);
PAINT GREEN (4700 -300);
DISPLAY INVISIBLE (4700 -300);
FORCEPROP 1 LAST PATH I115
R 2
J 0
(4600 -480);
DISPLAY 0.723404 (4600 -480);
PAINT GREEN (4600 -480);
DISPLAY INVISIBLE (4600 -480);
FORCEPROP 0 LAST CDS_LOCATION X32
J 0
(4575 125);
DISPLAY 1.021277 (4575 125);
DISPLAY INVISIBLE (4575 125);
FORCEPROP 0 LAST $SEC 1
J 0
(4575 125);
DISPLAY 0.680851 (4575 125);
PAINT MONO (4575 125);
DISPLAY INVISIBLE (4575 125);
FORCEPROP 0 LAST CDS_SEC 1
J 0
(4575 125);
DISPLAY 1.021277 (4575 125);
DISPLAY INVISIBLE (4575 125);
FORCEADD TP_TDR_4P_FTS..1
(3375 475);
FORCEPROP 1 LAST PART_NUMBER TP15
J 0
(3250 710);
DISPLAY 0.723404 (3250 710);
PAINT GREEN (3250 710);
DISPLAY INVISIBLE (3250 710);
FORCEPROP 1 LAST MATERIAL EMPTY
J 0
(3250 660);
DISPLAY 0.723404 (3250 660);
PAINT GREEN (3250 660);
FORCEPROP 2 LAST PACK_TYPE TH
J 0
(3250 800);
DISPLAY 1.021277 (3250 800);
FORCEPROP 2 LAST VALUE TP_TDR_4P_DIP
J 0
(3250 850);
DISPLAY 1.021277 (3250 850);
FORCEPROP 1 LAST $LOCATION X29
J 0
(3250 755);
DISPLAY 0.723404 (3250 755);
PAINT GREEN (3250 755);
FORCEPROP 0 LASTPIN (3100 550) $PN 2
J 2
(3090 560);
DISPLAY 0.680851 (3090 560);
PAINT MONO (3090 560);
FORCEPROP 0 LASTPIN (3100 400) $PN 3
J 2
(3090 410);
DISPLAY 0.680851 (3090 410);
PAINT MONO (3090 410);
FORCEPROP 0 LASTPIN (3650 550) $PN 1
J 0
(3660 560);
DISPLAY 0.680851 (3660 560);
PAINT MONO (3660 560);
FORCEPROP 0 LASTPIN (3650 400) $PN 4
J 0
(3660 410);
DISPLAY 0.680851 (3660 410);
PAINT MONO (3660 410);
FORCEPROP 2 LAST CDS_LIB pure_quanta
J 0
(3375 475);
DISPLAY INVISIBLE (3375 475);
FORCEPROP 1 LAST NEEDS_NO_SIZE TRUE
J 0
(3375 475);
DISPLAY 0.468085 (3375 475);
PAINT GREEN (3375 475);
DISPLAY INVISIBLE (3375 475);
FORCEPROP 1 LAST PATH I116
J 0
(3475 655);
DISPLAY 0.723404 (3475 655);
PAINT GREEN (3475 655);
DISPLAY INVISIBLE (3475 655);
FORCEPROP 0 LAST CDS_LOCATION X29
J 0
(3250 900);
DISPLAY 1.021277 (3250 900);
DISPLAY INVISIBLE (3250 900);
FORCEPROP 0 LAST $SEC 1
J 0
(3250 900);
DISPLAY 0.680851 (3250 900);
PAINT MONO (3250 900);
DISPLAY INVISIBLE (3250 900);
FORCEPROP 0 LAST CDS_SEC 1
J 0
(3250 900);
DISPLAY 1.021277 (3250 900);
DISPLAY INVISIBLE (3250 900);
FORCEADD TP_TDR_4P_FTS..1
(3375 -300);
FORCEPROP 1 LAST PART_NUMBER TP15
J 0
(3250 -65);
DISPLAY 0.723404 (3250 -65);
PAINT GREEN (3250 -65);
DISPLAY INVISIBLE (3250 -65);
FORCEPROP 1 LAST MATERIAL EMPTY
J 0
(3250 -115);
DISPLAY 0.723404 (3250 -115);
PAINT GREEN (3250 -115);
FORCEPROP 2 LAST VALUE TP_TDR_4P_DIP
J 0
(3250 75);
DISPLAY 1.021277 (3250 75);
FORCEPROP 2 LAST PACK_TYPE TH
J 0
(3250 25);
DISPLAY 1.021277 (3250 25);
FORCEPROP 1 LAST $LOCATION X30
J 0
(3250 -20);
DISPLAY 0.723404 (3250 -20);
PAINT GREEN (3250 -20);
FORCEPROP 0 LASTPIN (3100 -225) $PN 2
J 2
(3090 -215);
DISPLAY 0.680851 (3090 -215);
PAINT MONO (3090 -215);
FORCEPROP 0 LASTPIN (3100 -375) $PN 3
J 2
(3090 -365);
DISPLAY 0.680851 (3090 -365);
PAINT MONO (3090 -365);
FORCEPROP 0 LASTPIN (3650 -225) $PN 1
J 0
(3660 -215);
DISPLAY 0.680851 (3660 -215);
PAINT MONO (3660 -215);
FORCEPROP 0 LASTPIN (3650 -375) $PN 4
J 0
(3660 -365);
DISPLAY 0.680851 (3660 -365);
PAINT MONO (3660 -365);
FORCEPROP 2 LAST CDS_LIB pure_quanta
J 0
(3375 -300);
DISPLAY INVISIBLE (3375 -300);
FORCEPROP 1 LAST NEEDS_NO_SIZE TRUE
J 0
(3375 -300);
DISPLAY 0.468085 (3375 -300);
PAINT GREEN (3375 -300);
DISPLAY INVISIBLE (3375 -300);
FORCEPROP 1 LAST PATH I117
J 0
(3475 -120);
DISPLAY 0.723404 (3475 -120);
PAINT GREEN (3475 -120);
DISPLAY INVISIBLE (3475 -120);
FORCEPROP 0 LAST CDS_LOCATION X30
J 0
(3250 125);
DISPLAY 1.021277 (3250 125);
DISPLAY INVISIBLE (3250 125);
FORCEPROP 0 LAST $SEC 1
J 0
(3250 125);
DISPLAY 0.680851 (3250 125);
PAINT MONO (3250 125);
DISPLAY INVISIBLE (3250 125);
FORCEPROP 0 LAST CDS_SEC 1
J 0
(3250 125);
DISPLAY 1.021277 (3250 125);
DISPLAY INVISIBLE (3250 125);
FORCEADD UNIVERSAL_GND..1
(2950 250);
FORCEPROP 3 LASTPIN (2950 300) SIG_NAME T1_GND\g
J 0
(2960 310);
DISPLAY 0.659574 (2960 310);
PAINT MONO (2960 310);
DISPLAY INVISIBLE (2960 310);
FORCEPROP 1 LAST HDL_POWER T1_GND
J 1
(2975 175);
DISPLAY 0.872340 (2975 175);
PAINT GREEN (2975 175);
FORCEPROP 2 LAST CDS_LIB logical_power
J 0
(2950 250);
DISPLAY INVISIBLE (2950 250);
FORCEPROP 1 LAST PATH I118
J 0
(3025 250);
DISPLAY 0.872340 (3025 250);
PAINT AQUA (3025 250);
DISPLAY INVISIBLE (3025 250);
FORCEADD UNIVERSAL_GND..1
(2950 -525);
FORCEPROP 3 LASTPIN (2950 -475) SIG_NAME T1_GND\g
J 0
(2960 -465);
DISPLAY 0.659574 (2960 -465);
PAINT MONO (2960 -465);
DISPLAY INVISIBLE (2960 -465);
FORCEPROP 1 LAST HDL_POWER T1_GND
J 1
(2975 -600);
DISPLAY 0.872340 (2975 -600);
PAINT GREEN (2975 -600);
FORCEPROP 2 LAST CDS_LIB logical_power
J 0
(2950 -525);
DISPLAY INVISIBLE (2950 -525);
FORCEPROP 1 LAST PATH I119
J 0
(3025 -525);
DISPLAY 0.872340 (3025 -525);
PAINT AQUA (3025 -525);
DISPLAY INVISIBLE (3025 -525);
FORCEADD TP_TDR_4P_FTS..1
(3400 3475);
FORCEPROP 1 LAST PART_NUMBER TP15
J 0
(3275 3710);
DISPLAY 0.723404 (3275 3710);
PAINT GREEN (3275 3710);
DISPLAY INVISIBLE (3275 3710);
FORCEPROP 2 LAST PACK_TYPE TH
J 0
(3275 3800);
DISPLAY 1.021277 (3275 3800);
FORCEPROP 1 LAST MATERIAL EMPTY
J 0
(3275 3660);
DISPLAY 0.723404 (3275 3660);
PAINT GREEN (3275 3660);
FORCEPROP 2 LAST VALUE TP_TDR_4P_DIP
J 0
(3275 3850);
DISPLAY 1.021277 (3275 3850);
FORCEPROP 1 LAST $LOCATION X14
J 0
(3275 3755);
DISPLAY 0.723404 (3275 3755);
PAINT GREEN (3275 3755);
FORCEPROP 0 LASTPIN (3125 3550) $PN 2
J 2
(3115 3560);
DISPLAY 0.680851 (3115 3560);
PAINT MONO (3115 3560);
FORCEPROP 0 LASTPIN (3125 3400) $PN 3
J 2
(3115 3410);
DISPLAY 0.680851 (3115 3410);
PAINT MONO (3115 3410);
FORCEPROP 0 LASTPIN (3675 3550) $PN 1
J 0
(3685 3560);
DISPLAY 0.680851 (3685 3560);
PAINT MONO (3685 3560);
FORCEPROP 0 LASTPIN (3675 3400) $PN 4
J 0
(3685 3410);
DISPLAY 0.680851 (3685 3410);
PAINT MONO (3685 3410);
FORCEPROP 1 LAST NEEDS_NO_SIZE TRUE
J 0
(3400 3475);
DISPLAY 0.468085 (3400 3475);
PAINT GREEN (3400 3475);
DISPLAY INVISIBLE (3400 3475);
FORCEPROP 2 LAST CDS_LIB pure_quanta
J 0
(3400 3475);
DISPLAY INVISIBLE (3400 3475);
FORCEPROP 1 LAST PATH I12
J 0
(3500 3655);
DISPLAY 0.723404 (3500 3655);
PAINT GREEN (3500 3655);
DISPLAY INVISIBLE (3500 3655);
FORCEPROP 0 LAST CDS_LOCATION X14
J 0
(3275 3900);
DISPLAY 1.021277 (3275 3900);
DISPLAY INVISIBLE (3275 3900);
FORCEPROP 0 LAST $SEC 1
J 0
(3275 3900);
DISPLAY 0.680851 (3275 3900);
PAINT MONO (3275 3900);
DISPLAY INVISIBLE (3275 3900);
FORCEPROP 0 LAST CDS_SEC 1
J 0
(3275 3900);
DISPLAY 1.021277 (3275 3900);
DISPLAY INVISIBLE (3275 3900);
FORCEADD UNIVERSAL_GND..1
(2975 4025);
FORCEPROP 3 LASTPIN (2975 4075) SIG_NAME T1_GND\g
J 0
(2985 4085);
DISPLAY 0.659574 (2985 4085);
PAINT MONO (2985 4085);
DISPLAY INVISIBLE (2985 4085);
FORCEPROP 1 LAST HDL_POWER T1_GND
J 1
(3000 3950);
DISPLAY 0.872340 (3000 3950);
PAINT GREEN (3000 3950);
FORCEPROP 2 LAST CDS_LIB logical_power
J 0
(2975 4025);
PAINT MONO (2975 4025);
DISPLAY INVISIBLE (2975 4025);
FORCEPROP 1 LAST PATH I13
J 0
(3050 4025);
DISPLAY 0.872340 (3050 4025);
PAINT AQUA (3050 4025);
DISPLAY INVISIBLE (3050 4025);
FORCEADD TP_TDR_4P_FTS..1
(3400 2700);
FORCEPROP 1 LAST PART_NUMBER TP15
J 0
(3275 2935);
DISPLAY 0.723404 (3275 2935);
PAINT GREEN (3275 2935);
DISPLAY INVISIBLE (3275 2935);
FORCEPROP 1 LAST MATERIAL EMPTY
J 0
(3275 2885);
DISPLAY 0.723404 (3275 2885);
PAINT GREEN (3275 2885);
FORCEPROP 2 LAST VALUE TP_TDR_4P_DIP
J 0
(3275 3075);
DISPLAY 1.021277 (3275 3075);
FORCEPROP 2 LAST PACK_TYPE TH
J 0
(3275 3025);
DISPLAY 1.021277 (3275 3025);
FORCEPROP 1 LAST $LOCATION X15
J 0
(3275 2980);
DISPLAY 0.723404 (3275 2980);
PAINT GREEN (3275 2980);
FORCEPROP 0 LASTPIN (3125 2775) $PN 2
J 2
(3115 2785);
DISPLAY 0.680851 (3115 2785);
PAINT MONO (3115 2785);
FORCEPROP 0 LASTPIN (3125 2625) $PN 3
J 2
(3115 2635);
DISPLAY 0.680851 (3115 2635);
PAINT MONO (3115 2635);
FORCEPROP 0 LASTPIN (3675 2775) $PN 1
J 0
(3685 2785);
DISPLAY 0.680851 (3685 2785);
PAINT MONO (3685 2785);
FORCEPROP 0 LASTPIN (3675 2625) $PN 4
J 0
(3685 2635);
DISPLAY 0.680851 (3685 2635);
PAINT MONO (3685 2635);
FORCEPROP 2 LAST CDS_LIB pure_quanta
J 0
(3400 2700);
DISPLAY INVISIBLE (3400 2700);
FORCEPROP 1 LAST NEEDS_NO_SIZE TRUE
J 0
(3400 2700);
DISPLAY 0.468085 (3400 2700);
PAINT GREEN (3400 2700);
DISPLAY INVISIBLE (3400 2700);
FORCEPROP 1 LAST PATH I17
J 0
(3500 2880);
DISPLAY 0.723404 (3500 2880);
PAINT GREEN (3500 2880);
DISPLAY INVISIBLE (3500 2880);
FORCEPROP 0 LAST CDS_LOCATION X15
J 0
(3275 3125);
DISPLAY 1.021277 (3275 3125);
DISPLAY INVISIBLE (3275 3125);
FORCEPROP 0 LAST $SEC 1
J 0
(3275 3125);
DISPLAY 0.680851 (3275 3125);
PAINT MONO (3275 3125);
DISPLAY INVISIBLE (3275 3125);
FORCEPROP 0 LAST CDS_SEC 1
J 0
(3275 3125);
DISPLAY 1.021277 (3275 3125);
DISPLAY INVISIBLE (3275 3125);
FORCEADD TP_TDR_4P_FTS..1
(3400 1925);
FORCEPROP 1 LAST PART_NUMBER TP15
J 0
(3275 2160);
DISPLAY 0.723404 (3275 2160);
PAINT GREEN (3275 2160);
DISPLAY INVISIBLE (3275 2160);
FORCEPROP 2 LAST PACK_TYPE TH
J 0
(3275 2250);
DISPLAY 1.021277 (3275 2250);
FORCEPROP 1 LAST MATERIAL EMPTY
J 0
(3275 2110);
DISPLAY 0.723404 (3275 2110);
PAINT GREEN (3275 2110);
FORCEPROP 2 LAST VALUE TP_TDR_4P_DIP
J 0
(3275 2300);
DISPLAY 1.021277 (3275 2300);
FORCEPROP 1 LAST $LOCATION X16
J 0
(3275 2205);
DISPLAY 0.723404 (3275 2205);
PAINT GREEN (3275 2205);
FORCEPROP 0 LASTPIN (3125 2000) $PN 2
J 2
(3115 2010);
DISPLAY 0.680851 (3115 2010);
PAINT MONO (3115 2010);
FORCEPROP 0 LASTPIN (3125 1850) $PN 3
J 2
(3115 1860);
DISPLAY 0.680851 (3115 1860);
PAINT MONO (3115 1860);
FORCEPROP 0 LASTPIN (3675 2000) $PN 1
J 0
(3685 2010);
DISPLAY 0.680851 (3685 2010);
PAINT MONO (3685 2010);
FORCEPROP 0 LASTPIN (3675 1850) $PN 4
J 0
(3685 1860);
DISPLAY 0.680851 (3685 1860);
PAINT MONO (3685 1860);
FORCEPROP 1 LAST PATH I18
J 0
(3500 2105);
DISPLAY 0.723404 (3500 2105);
PAINT GREEN (3500 2105);
DISPLAY INVISIBLE (3500 2105);
FORCEPROP 1 LAST NEEDS_NO_SIZE TRUE
J 0
(3400 1925);
DISPLAY 0.468085 (3400 1925);
PAINT GREEN (3400 1925);
DISPLAY INVISIBLE (3400 1925);
FORCEPROP 2 LAST CDS_LIB pure_quanta
J 0
(3400 1925);
DISPLAY INVISIBLE (3400 1925);
FORCEPROP 0 LAST CDS_LOCATION X16
J 0
(3275 2350);
DISPLAY 1.021277 (3275 2350);
DISPLAY INVISIBLE (3275 2350);
FORCEPROP 0 LAST $SEC 1
J 0
(3275 2350);
DISPLAY 0.680851 (3275 2350);
PAINT MONO (3275 2350);
DISPLAY INVISIBLE (3275 2350);
FORCEPROP 0 LAST CDS_SEC 1
J 0
(3275 2350);
DISPLAY 1.021277 (3275 2350);
DISPLAY INVISIBLE (3275 2350);
FORCEADD TP_TDR_4P_FTS..1
(3400 1150);
FORCEPROP 1 LAST PART_NUMBER TP15
J 0
(3275 1385);
DISPLAY 0.723404 (3275 1385);
PAINT GREEN (3275 1385);
DISPLAY INVISIBLE (3275 1385);
FORCEPROP 2 LAST PACK_TYPE TH
J 0
(3275 1475);
DISPLAY 1.021277 (3275 1475);
FORCEPROP 1 LAST MATERIAL EMPTY
J 0
(3275 1335);
DISPLAY 0.723404 (3275 1335);
PAINT GREEN (3275 1335);
FORCEPROP 2 LAST VALUE TP_TDR_4P_DIP
J 0
(3275 1525);
DISPLAY 1.021277 (3275 1525);
FORCEPROP 1 LAST $LOCATION X17
J 0
(3275 1430);
DISPLAY 0.723404 (3275 1430);
PAINT GREEN (3275 1430);
FORCEPROP 0 LASTPIN (3125 1225) $PN 2
J 2
(3115 1235);
DISPLAY 0.680851 (3115 1235);
PAINT MONO (3115 1235);
FORCEPROP 0 LASTPIN (3125 1075) $PN 3
J 2
(3115 1085);
DISPLAY 0.680851 (3115 1085);
PAINT MONO (3115 1085);
FORCEPROP 0 LASTPIN (3675 1225) $PN 1
J 0
(3685 1235);
DISPLAY 0.680851 (3685 1235);
PAINT MONO (3685 1235);
FORCEPROP 0 LASTPIN (3675 1075) $PN 4
J 0
(3685 1085);
DISPLAY 0.680851 (3685 1085);
PAINT MONO (3685 1085);
FORCEPROP 1 LAST PATH I19
J 0
(3500 1330);
DISPLAY 0.723404 (3500 1330);
PAINT GREEN (3500 1330);
DISPLAY INVISIBLE (3500 1330);
FORCEPROP 1 LAST NEEDS_NO_SIZE TRUE
J 0
(3400 1150);
DISPLAY 0.468085 (3400 1150);
PAINT GREEN (3400 1150);
DISPLAY INVISIBLE (3400 1150);
FORCEPROP 2 LAST CDS_LIB pure_quanta
J 0
(3400 1150);
DISPLAY INVISIBLE (3400 1150);
FORCEPROP 0 LAST CDS_LOCATION X17
J 0
(3275 1575);
DISPLAY 1.021277 (3275 1575);
DISPLAY INVISIBLE (3275 1575);
FORCEPROP 0 LAST $SEC 1
J 0
(3275 1575);
DISPLAY 0.680851 (3275 1575);
PAINT MONO (3275 1575);
DISPLAY INVISIBLE (3275 1575);
FORCEPROP 0 LAST CDS_SEC 1
J 0
(3275 1575);
DISPLAY 1.021277 (3275 1575);
DISPLAY INVISIBLE (3275 1575);
FORCEADD TP_TDR_4P_FTS..1
R 4
(2025 4250);
FORCEPROP 1 LAST PART_NUMBER TP15
J 0
(1900 4590);
DISPLAY 0.723404 (1900 4590);
PAINT GREEN (1900 4590);
DISPLAY INVISIBLE (1900 4590);
FORCEPROP 1 LAST MATERIAL EMPTY
J 0
(1900 4640);
DISPLAY 0.723404 (1900 4640);
PAINT GREEN (1900 4640);
FORCEPROP 2 LAST PACK_TYPE TH
J 0
(1900 4500);
DISPLAY 1.021277 (1900 4500);
FORCEPROP 2 LAST VALUE TP_TDR_4P_DIP
J 0
(1900 4450);
DISPLAY 1.021277 (1900 4450);
FORCEPROP 1 LAST $LOCATION X7
J 0
(1900 4545);
DISPLAY 0.723404 (1900 4545);
PAINT GREEN (1900 4545);
FORCEPROP 0 LASTPIN (2300 4175) $PN 2
J 0
(2310 4185);
DISPLAY 0.680851 (2310 4185);
PAINT MONO (2310 4185);
FORCEPROP 0 LASTPIN (2300 4325) $PN 3
J 0
(2310 4335);
DISPLAY 0.680851 (2310 4335);
PAINT MONO (2310 4335);
FORCEPROP 0 LASTPIN (1750 4175) $PN 1
J 2
(1740 4185);
DISPLAY 0.680851 (1740 4185);
PAINT MONO (1740 4185);
FORCEPROP 0 LASTPIN (1750 4325) $PN 4
J 2
(1740 4335);
DISPLAY 0.680851 (1740 4335);
PAINT MONO (1740 4335);
FORCEPROP 2 LAST CDS_LIB pure_quanta
R 2
J 0
(2025 4250);
DISPLAY INVISIBLE (2025 4250);
FORCEPROP 1 LAST NEEDS_NO_SIZE TRUE
R 2
J 0
(2025 4250);
DISPLAY 0.468085 (2025 4250);
PAINT GREEN (2025 4250);
DISPLAY INVISIBLE (2025 4250);
FORCEPROP 1 LAST PATH I26
R 2
J 0
(1925 4070);
DISPLAY 0.723404 (1925 4070);
PAINT GREEN (1925 4070);
DISPLAY INVISIBLE (1925 4070);
FORCEPROP 0 LAST CDS_LOCATION X7
J 0
(1900 4675);
DISPLAY 1.021277 (1900 4675);
DISPLAY INVISIBLE (1900 4675);
FORCEPROP 0 LAST $SEC 1
J 0
(1900 4675);
DISPLAY 0.680851 (1900 4675);
PAINT MONO (1900 4675);
DISPLAY INVISIBLE (1900 4675);
FORCEPROP 0 LAST CDS_SEC 1
J 0
(1900 4675);
DISPLAY 1.021277 (1900 4675);
DISPLAY INVISIBLE (1900 4675);
FORCEADD TP_TDR_4P_FTS..1
R 4
(2025 3475);
FORCEPROP 1 LAST PART_NUMBER TP15
J 0
(1900 3815);
DISPLAY 0.723404 (1900 3815);
PAINT GREEN (1900 3815);
DISPLAY INVISIBLE (1900 3815);
FORCEPROP 1 LAST MATERIAL EMPTY
J 0
(1900 3865);
DISPLAY 0.723404 (1900 3865);
PAINT GREEN (1900 3865);
FORCEPROP 2 LAST VALUE TP_TDR_4P_DIP
J 0
(1900 3675);
DISPLAY 1.021277 (1900 3675);
FORCEPROP 2 LAST PACK_TYPE TH
J 0
(1900 3725);
DISPLAY 1.021277 (1900 3725);
FORCEPROP 1 LAST $LOCATION X8
J 0
(1900 3770);
DISPLAY 0.723404 (1900 3770);
PAINT GREEN (1900 3770);
FORCEPROP 0 LASTPIN (2300 3400) $PN 2
J 0
(2310 3410);
DISPLAY 0.680851 (2310 3410);
PAINT MONO (2310 3410);
FORCEPROP 0 LASTPIN (2300 3550) $PN 3
J 0
(2310 3560);
DISPLAY 0.680851 (2310 3560);
PAINT MONO (2310 3560);
FORCEPROP 0 LASTPIN (1750 3400) $PN 1
J 2
(1740 3410);
DISPLAY 0.680851 (1740 3410);
PAINT MONO (1740 3410);
FORCEPROP 0 LASTPIN (1750 3550) $PN 4
J 2
(1740 3560);
DISPLAY 0.680851 (1740 3560);
PAINT MONO (1740 3560);
FORCEPROP 2 LAST CDS_LIB pure_quanta
R 2
J 0
(2025 3475);
DISPLAY INVISIBLE (2025 3475);
FORCEPROP 1 LAST NEEDS_NO_SIZE TRUE
R 2
J 0
(2025 3475);
DISPLAY 0.468085 (2025 3475);
PAINT GREEN (2025 3475);
DISPLAY INVISIBLE (2025 3475);
FORCEPROP 1 LAST PATH I27
R 2
J 0
(1925 3295);
DISPLAY 0.723404 (1925 3295);
PAINT GREEN (1925 3295);
DISPLAY INVISIBLE (1925 3295);
FORCEPROP 0 LAST CDS_LOCATION X8
J 0
(1900 3900);
DISPLAY 1.021277 (1900 3900);
DISPLAY INVISIBLE (1900 3900);
FORCEPROP 0 LAST $SEC 1
J 0
(1900 3900);
DISPLAY 0.680851 (1900 3900);
PAINT MONO (1900 3900);
DISPLAY INVISIBLE (1900 3900);
FORCEPROP 0 LAST CDS_SEC 1
J 0
(1900 3900);
DISPLAY 1.021277 (1900 3900);
DISPLAY INVISIBLE (1900 3900);
FORCEADD TP_TDR_4P_FTS..1
(700 4250);
FORCEPROP 1 LAST PART_NUMBER TP15
J 0
(575 4485);
DISPLAY 0.723404 (575 4485);
PAINT GREEN (575 4485);
DISPLAY INVISIBLE (575 4485);
FORCEPROP 1 LAST MATERIAL EMPTY
J 0
(575 4435);
DISPLAY 0.723404 (575 4435);
PAINT GREEN (575 4435);
FORCEPROP 2 LAST VALUE TP_TDR_4P_DIP
J 0
(575 4625);
DISPLAY 1.021277 (575 4625);
FORCEPROP 2 LAST PACK_TYPE TH
J 0
(575 4575);
DISPLAY 1.021277 (575 4575);
FORCEPROP 1 LAST $LOCATION X1
J 0
(575 4530);
DISPLAY 0.723404 (575 4530);
PAINT GREEN (575 4530);
FORCEPROP 0 LASTPIN (425 4325) $PN 2
J 2
(415 4335);
DISPLAY 0.680851 (415 4335);
PAINT MONO (415 4335);
FORCEPROP 0 LASTPIN (425 4175) $PN 3
J 2
(415 4185);
DISPLAY 0.680851 (415 4185);
PAINT MONO (415 4185);
FORCEPROP 0 LASTPIN (975 4325) $PN 1
J 0
(985 4335);
DISPLAY 0.680851 (985 4335);
PAINT MONO (985 4335);
FORCEPROP 0 LASTPIN (975 4175) $PN 4
J 0
(985 4185);
DISPLAY 0.680851 (985 4185);
PAINT MONO (985 4185);
FORCEPROP 2 LAST CDS_LIB pure_quanta
J 0
(700 4250);
DISPLAY INVISIBLE (700 4250);
FORCEPROP 1 LAST NEEDS_NO_SIZE TRUE
J 0
(700 4250);
DISPLAY 0.468085 (700 4250);
PAINT GREEN (700 4250);
DISPLAY INVISIBLE (700 4250);
FORCEPROP 1 LAST PATH I28
J 0
(800 4430);
DISPLAY 0.723404 (800 4430);
PAINT GREEN (800 4430);
DISPLAY INVISIBLE (800 4430);
FORCEPROP 0 LAST CDS_LOCATION X1
J 0
(575 4675);
DISPLAY 1.021277 (575 4675);
DISPLAY INVISIBLE (575 4675);
FORCEPROP 0 LAST $SEC 1
J 0
(575 4675);
DISPLAY 0.680851 (575 4675);
PAINT MONO (575 4675);
DISPLAY INVISIBLE (575 4675);
FORCEPROP 0 LAST CDS_SEC 1
J 0
(575 4675);
DISPLAY 1.021277 (575 4675);
DISPLAY INVISIBLE (575 4675);
FORCEADD TP_TDR_4P_FTS..1
R 4
(4725 4250);
FORCEPROP 1 LAST PART_NUMBER TP15
J 0
(4600 4590);
DISPLAY 0.723404 (4600 4590);
PAINT GREEN (4600 4590);
DISPLAY INVISIBLE (4600 4590);
FORCEPROP 2 LAST VALUE TP_TDR_4P_DIP
J 0
(4600 4450);
DISPLAY 1.021277 (4600 4450);
FORCEPROP 2 LAST PACK_TYPE TH
J 0
(4600 4500);
DISPLAY 1.021277 (4600 4500);
FORCEPROP 1 LAST MATERIAL EMPTY
J 0
(4600 4640);
DISPLAY 0.723404 (4600 4640);
PAINT GREEN (4600 4640);
FORCEPROP 1 LAST $LOCATION X19
J 0
(4600 4545);
DISPLAY 0.723404 (4600 4545);
PAINT GREEN (4600 4545);
FORCEPROP 0 LASTPIN (5000 4175) $PN 2
J 0
(5010 4185);
DISPLAY 0.680851 (5010 4185);
PAINT MONO (5010 4185);
FORCEPROP 0 LASTPIN (5000 4325) $PN 3
J 0
(5010 4335);
DISPLAY 0.680851 (5010 4335);
PAINT MONO (5010 4335);
FORCEPROP 0 LASTPIN (4450 4175) $PN 1
J 2
(4440 4185);
DISPLAY 0.680851 (4440 4185);
PAINT MONO (4440 4185);
FORCEPROP 0 LASTPIN (4450 4325) $PN 4
J 2
(4440 4335);
DISPLAY 0.680851 (4440 4335);
PAINT MONO (4440 4335);
FORCEPROP 1 LAST NEEDS_NO_SIZE TRUE
R 2
J 0
(4725 4250);
DISPLAY 0.468085 (4725 4250);
PAINT GREEN (4725 4250);
DISPLAY INVISIBLE (4725 4250);
FORCEPROP 2 LAST CDS_LIB pure_quanta
R 2
J 0
(4725 4250);
DISPLAY INVISIBLE (4725 4250);
FORCEPROP 1 LAST PATH I3
R 2
J 0
(4625 4070);
DISPLAY 0.723404 (4625 4070);
PAINT GREEN (4625 4070);
DISPLAY INVISIBLE (4625 4070);
FORCEPROP 0 LAST CDS_LOCATION X19
J 0
(4600 4675);
DISPLAY 1.021277 (4600 4675);
DISPLAY INVISIBLE (4600 4675);
FORCEPROP 0 LAST $SEC 1
J 0
(4600 4675);
DISPLAY 0.680851 (4600 4675);
PAINT MONO (4600 4675);
DISPLAY INVISIBLE (4600 4675);
FORCEPROP 0 LAST CDS_SEC 1
J 0
(4600 4675);
DISPLAY 1.021277 (4600 4675);
DISPLAY INVISIBLE (4600 4675);
FORCEADD TP_TDR_4P_FTS..1
(700 3475);
FORCEPROP 1 LAST PART_NUMBER TP15
J 0
(575 3710);
DISPLAY 0.723404 (575 3710);
PAINT GREEN (575 3710);
DISPLAY INVISIBLE (575 3710);
FORCEPROP 2 LAST PACK_TYPE TH
J 0
(575 3800);
DISPLAY 1.021277 (575 3800);
FORCEPROP 2 LAST VALUE TP_TDR_4P_DIP
J 0
(575 3850);
DISPLAY 1.021277 (575 3850);
FORCEPROP 1 LAST MATERIAL EMPTY
J 0
(575 3660);
DISPLAY 0.723404 (575 3660);
PAINT GREEN (575 3660);
FORCEPROP 1 LAST $LOCATION X2
J 0
(575 3755);
DISPLAY 0.723404 (575 3755);
PAINT GREEN (575 3755);
FORCEPROP 0 LASTPIN (425 3550) $PN 2
J 2
(415 3560);
DISPLAY 0.680851 (415 3560);
PAINT MONO (415 3560);
FORCEPROP 0 LASTPIN (425 3400) $PN 3
J 2
(415 3410);
DISPLAY 0.680851 (415 3410);
PAINT MONO (415 3410);
FORCEPROP 0 LASTPIN (975 3550) $PN 1
J 0
(985 3560);
DISPLAY 0.680851 (985 3560);
PAINT MONO (985 3560);
FORCEPROP 0 LASTPIN (975 3400) $PN 4
J 0
(985 3410);
DISPLAY 0.680851 (985 3410);
PAINT MONO (985 3410);
FORCEPROP 2 LAST CDS_LIB pure_quanta
J 0
(700 3475);
DISPLAY INVISIBLE (700 3475);
FORCEPROP 1 LAST NEEDS_NO_SIZE TRUE
J 0
(700 3475);
DISPLAY 0.468085 (700 3475);
PAINT GREEN (700 3475);
DISPLAY INVISIBLE (700 3475);
FORCEPROP 1 LAST PATH I30
J 0
(800 3655);
DISPLAY 0.723404 (800 3655);
PAINT GREEN (800 3655);
DISPLAY INVISIBLE (800 3655);
FORCEPROP 0 LAST CDS_LOCATION X2
J 0
(575 3900);
DISPLAY 1.021277 (575 3900);
DISPLAY INVISIBLE (575 3900);
FORCEPROP 0 LAST $SEC 1
J 0
(575 3900);
DISPLAY 0.680851 (575 3900);
PAINT MONO (575 3900);
DISPLAY INVISIBLE (575 3900);
FORCEPROP 0 LAST CDS_SEC 1
J 0
(575 3900);
DISPLAY 1.021277 (575 3900);
DISPLAY INVISIBLE (575 3900);
FORCEADD TP_TDR_4P_FTS..1
R 4
(2025 2700);
FORCEPROP 1 LAST PART_NUMBER TP15
J 0
(1900 3040);
DISPLAY 0.723404 (1900 3040);
PAINT GREEN (1900 3040);
DISPLAY INVISIBLE (1900 3040);
FORCEPROP 2 LAST PACK_TYPE TH
J 0
(1900 2950);
DISPLAY 1.021277 (1900 2950);
FORCEPROP 1 LAST MATERIAL EMPTY
J 0
(1900 3090);
DISPLAY 0.723404 (1900 3090);
PAINT GREEN (1900 3090);
FORCEPROP 2 LAST VALUE TP_TDR_4P_DIP
J 0
(1900 2900);
DISPLAY 1.021277 (1900 2900);
FORCEPROP 1 LAST $LOCATION X9
J 0
(1900 2995);
DISPLAY 0.723404 (1900 2995);
PAINT GREEN (1900 2995);
FORCEPROP 0 LASTPIN (2300 2625) $PN 2
J 0
(2310 2635);
DISPLAY 0.680851 (2310 2635);
PAINT MONO (2310 2635);
FORCEPROP 0 LASTPIN (2300 2775) $PN 3
J 0
(2310 2785);
DISPLAY 0.680851 (2310 2785);
PAINT MONO (2310 2785);
FORCEPROP 0 LASTPIN (1750 2625) $PN 1
J 2
(1740 2635);
DISPLAY 0.680851 (1740 2635);
PAINT MONO (1740 2635);
FORCEPROP 0 LASTPIN (1750 2775) $PN 4
J 2
(1740 2785);
DISPLAY 0.680851 (1740 2785);
PAINT MONO (1740 2785);
FORCEPROP 1 LAST NEEDS_NO_SIZE TRUE
R 2
J 0
(2025 2700);
DISPLAY 0.468085 (2025 2700);
PAINT GREEN (2025 2700);
DISPLAY INVISIBLE (2025 2700);
FORCEPROP 2 LAST CDS_LIB pure_quanta
R 2
J 0
(2025 2700);
DISPLAY INVISIBLE (2025 2700);
FORCEPROP 1 LAST PATH I32
R 2
J 0
(1925 2520);
DISPLAY 0.723404 (1925 2520);
PAINT GREEN (1925 2520);
DISPLAY INVISIBLE (1925 2520);
FORCEPROP 0 LAST CDS_LOCATION X9
J 0
(1900 3125);
DISPLAY 1.021277 (1900 3125);
DISPLAY INVISIBLE (1900 3125);
FORCEPROP 0 LAST $SEC 1
J 0
(1900 3125);
DISPLAY 0.680851 (1900 3125);
PAINT MONO (1900 3125);
DISPLAY INVISIBLE (1900 3125);
FORCEPROP 0 LAST CDS_SEC 1
J 0
(1900 3125);
DISPLAY 1.021277 (1900 3125);
DISPLAY INVISIBLE (1900 3125);
FORCEADD TP_TDR_4P_FTS..1
R 4
(2025 1925);
FORCEPROP 1 LAST PART_NUMBER TP15
J 0
(1900 2265);
DISPLAY 0.723404 (1900 2265);
PAINT GREEN (1900 2265);
DISPLAY INVISIBLE (1900 2265);
FORCEPROP 2 LAST VALUE TP_TDR_4P_DIP
J 0
(1900 2125);
DISPLAY 1.021277 (1900 2125);
FORCEPROP 2 LAST PACK_TYPE TH
J 0
(1900 2175);
DISPLAY 1.021277 (1900 2175);
FORCEPROP 1 LAST MATERIAL EMPTY
J 0
(1900 2315);
DISPLAY 0.723404 (1900 2315);
PAINT GREEN (1900 2315);
FORCEPROP 1 LAST $LOCATION X10
J 0
(1900 2220);
DISPLAY 0.723404 (1900 2220);
PAINT GREEN (1900 2220);
FORCEPROP 0 LASTPIN (2300 1850) $PN 2
J 0
(2310 1860);
DISPLAY 0.680851 (2310 1860);
PAINT MONO (2310 1860);
FORCEPROP 0 LASTPIN (2300 2000) $PN 3
J 0
(2310 2010);
DISPLAY 0.680851 (2310 2010);
PAINT MONO (2310 2010);
FORCEPROP 0 LASTPIN (1750 1850) $PN 1
J 2
(1740 1860);
DISPLAY 0.680851 (1740 1860);
PAINT MONO (1740 1860);
FORCEPROP 0 LASTPIN (1750 2000) $PN 4
J 2
(1740 2010);
DISPLAY 0.680851 (1740 2010);
PAINT MONO (1740 2010);
FORCEPROP 1 LAST NEEDS_NO_SIZE TRUE
R 2
J 0
(2025 1925);
DISPLAY 0.468085 (2025 1925);
PAINT GREEN (2025 1925);
DISPLAY INVISIBLE (2025 1925);
FORCEPROP 2 LAST CDS_LIB pure_quanta
R 2
J 0
(2025 1925);
DISPLAY INVISIBLE (2025 1925);
FORCEPROP 1 LAST PATH I33
R 2
J 0
(1925 1745);
DISPLAY 0.723404 (1925 1745);
PAINT GREEN (1925 1745);
DISPLAY INVISIBLE (1925 1745);
FORCEPROP 0 LAST CDS_LOCATION X10
J 0
(1900 2350);
DISPLAY 1.021277 (1900 2350);
DISPLAY INVISIBLE (1900 2350);
FORCEPROP 0 LAST $SEC 1
J 0
(1900 2350);
DISPLAY 0.680851 (1900 2350);
PAINT MONO (1900 2350);
DISPLAY INVISIBLE (1900 2350);
FORCEPROP 0 LAST CDS_SEC 1
J 0
(1900 2350);
DISPLAY 1.021277 (1900 2350);
DISPLAY INVISIBLE (1900 2350);
FORCEADD TP_TDR_4P_FTS..1
R 4
(2025 1150);
FORCEPROP 1 LAST PART_NUMBER TP15
J 0
(1900 1490);
DISPLAY 0.723404 (1900 1490);
PAINT GREEN (1900 1490);
DISPLAY INVISIBLE (1900 1490);
FORCEPROP 1 LAST MATERIAL EMPTY
J 0
(1900 1540);
DISPLAY 0.723404 (1900 1540);
PAINT GREEN (1900 1540);
FORCEPROP 2 LAST PACK_TYPE TH
J 0
(1900 1400);
DISPLAY 1.021277 (1900 1400);
FORCEPROP 2 LAST VALUE TP_TDR_4P_DIP
J 0
(1900 1350);
DISPLAY 1.021277 (1900 1350);
FORCEPROP 1 LAST $LOCATION X11
J 0
(1900 1445);
DISPLAY 0.723404 (1900 1445);
PAINT GREEN (1900 1445);
FORCEPROP 0 LASTPIN (2300 1075) $PN 2
J 0
(2310 1085);
DISPLAY 0.680851 (2310 1085);
PAINT MONO (2310 1085);
FORCEPROP 0 LASTPIN (2300 1225) $PN 3
J 0
(2310 1235);
DISPLAY 0.680851 (2310 1235);
PAINT MONO (2310 1235);
FORCEPROP 0 LASTPIN (1750 1075) $PN 1
J 2
(1740 1085);
DISPLAY 0.680851 (1740 1085);
PAINT MONO (1740 1085);
FORCEPROP 0 LASTPIN (1750 1225) $PN 4
J 2
(1740 1235);
DISPLAY 0.680851 (1740 1235);
PAINT MONO (1740 1235);
FORCEPROP 1 LAST NEEDS_NO_SIZE TRUE
R 2
J 0
(2025 1150);
DISPLAY 0.468085 (2025 1150);
PAINT GREEN (2025 1150);
DISPLAY INVISIBLE (2025 1150);
FORCEPROP 2 LAST CDS_LIB pure_quanta
R 2
J 0
(2025 1150);
DISPLAY INVISIBLE (2025 1150);
FORCEPROP 1 LAST PATH I34
R 2
J 0
(1925 970);
DISPLAY 0.723404 (1925 970);
PAINT GREEN (1925 970);
DISPLAY INVISIBLE (1925 970);
FORCEPROP 0 LAST CDS_LOCATION X11
J 0
(1900 1575);
DISPLAY 1.021277 (1900 1575);
DISPLAY INVISIBLE (1900 1575);
FORCEPROP 0 LAST $SEC 1
J 0
(1900 1575);
DISPLAY 0.680851 (1900 1575);
PAINT MONO (1900 1575);
DISPLAY INVISIBLE (1900 1575);
FORCEPROP 0 LAST CDS_SEC 1
J 0
(1900 1575);
DISPLAY 1.021277 (1900 1575);
DISPLAY INVISIBLE (1900 1575);
FORCEADD TP_TDR_4P_FTS..1
(700 2700);
FORCEPROP 1 LAST PART_NUMBER TP15
J 0
(575 2935);
DISPLAY 0.723404 (575 2935);
PAINT GREEN (575 2935);
DISPLAY INVISIBLE (575 2935);
FORCEPROP 2 LAST PACK_TYPE TH
J 0
(575 3025);
DISPLAY 1.021277 (575 3025);
FORCEPROP 1 LAST MATERIAL EMPTY
J 0
(575 2885);
DISPLAY 0.723404 (575 2885);
PAINT GREEN (575 2885);
FORCEPROP 2 LAST VALUE TP_TDR_4P_DIP
J 0
(575 3075);
DISPLAY 1.021277 (575 3075);
FORCEPROP 1 LAST $LOCATION X3
J 0
(575 2980);
DISPLAY 0.723404 (575 2980);
PAINT GREEN (575 2980);
FORCEPROP 0 LASTPIN (425 2775) $PN 2
J 2
(415 2785);
DISPLAY 0.680851 (415 2785);
PAINT MONO (415 2785);
FORCEPROP 0 LASTPIN (425 2625) $PN 3
J 2
(415 2635);
DISPLAY 0.680851 (415 2635);
PAINT MONO (415 2635);
FORCEPROP 0 LASTPIN (975 2775) $PN 1
J 0
(985 2785);
DISPLAY 0.680851 (985 2785);
PAINT MONO (985 2785);
FORCEPROP 0 LASTPIN (975 2625) $PN 4
J 0
(985 2635);
DISPLAY 0.680851 (985 2635);
PAINT MONO (985 2635);
FORCEPROP 1 LAST NEEDS_NO_SIZE TRUE
J 0
(700 2700);
DISPLAY 0.468085 (700 2700);
PAINT GREEN (700 2700);
DISPLAY INVISIBLE (700 2700);
FORCEPROP 2 LAST CDS_LIB pure_quanta
J 0
(700 2700);
DISPLAY INVISIBLE (700 2700);
FORCEPROP 1 LAST PATH I35
J 0
(800 2880);
DISPLAY 0.723404 (800 2880);
PAINT GREEN (800 2880);
DISPLAY INVISIBLE (800 2880);
FORCEPROP 0 LAST CDS_LOCATION X3
J 0
(575 3125);
DISPLAY 1.021277 (575 3125);
DISPLAY INVISIBLE (575 3125);
FORCEPROP 0 LAST $SEC 1
J 0
(575 3125);
DISPLAY 0.680851 (575 3125);
PAINT MONO (575 3125);
DISPLAY INVISIBLE (575 3125);
FORCEPROP 0 LAST CDS_SEC 1
J 0
(575 3125);
DISPLAY 1.021277 (575 3125);
DISPLAY INVISIBLE (575 3125);
FORCEADD TP_TDR_4P_FTS..1
(700 1925);
FORCEPROP 1 LAST PART_NUMBER TP15
J 0
(575 2160);
DISPLAY 0.723404 (575 2160);
PAINT GREEN (575 2160);
DISPLAY INVISIBLE (575 2160);
FORCEPROP 2 LAST VALUE TP_TDR_4P_DIP
J 0
(575 2300);
DISPLAY 1.021277 (575 2300);
FORCEPROP 2 LAST PACK_TYPE TH
J 0
(575 2250);
DISPLAY 1.021277 (575 2250);
FORCEPROP 1 LAST MATERIAL EMPTY
J 0
(575 2110);
DISPLAY 0.723404 (575 2110);
PAINT GREEN (575 2110);
FORCEPROP 1 LAST $LOCATION X4
J 0
(575 2205);
DISPLAY 0.723404 (575 2205);
PAINT GREEN (575 2205);
FORCEPROP 0 LASTPIN (425 2000) $PN 2
J 2
(415 2010);
DISPLAY 0.680851 (415 2010);
PAINT MONO (415 2010);
FORCEPROP 0 LASTPIN (425 1850) $PN 3
J 2
(415 1860);
DISPLAY 0.680851 (415 1860);
PAINT MONO (415 1860);
FORCEPROP 0 LASTPIN (975 2000) $PN 1
J 0
(985 2010);
DISPLAY 0.680851 (985 2010);
PAINT MONO (985 2010);
FORCEPROP 0 LASTPIN (975 1850) $PN 4
J 0
(985 1860);
DISPLAY 0.680851 (985 1860);
PAINT MONO (985 1860);
FORCEPROP 1 LAST NEEDS_NO_SIZE TRUE
J 0
(700 1925);
DISPLAY 0.468085 (700 1925);
PAINT GREEN (700 1925);
DISPLAY INVISIBLE (700 1925);
FORCEPROP 2 LAST CDS_LIB pure_quanta
J 0
(700 1925);
DISPLAY INVISIBLE (700 1925);
FORCEPROP 1 LAST PATH I37
J 0
(800 2105);
DISPLAY 0.723404 (800 2105);
PAINT GREEN (800 2105);
DISPLAY INVISIBLE (800 2105);
FORCEPROP 0 LAST CDS_LOCATION X4
J 0
(575 2350);
DISPLAY 1.021277 (575 2350);
DISPLAY INVISIBLE (575 2350);
FORCEPROP 0 LAST $SEC 1
J 0
(575 2350);
DISPLAY 0.680851 (575 2350);
PAINT MONO (575 2350);
DISPLAY INVISIBLE (575 2350);
FORCEPROP 0 LAST CDS_SEC 1
J 0
(575 2350);
DISPLAY 1.021277 (575 2350);
DISPLAY INVISIBLE (575 2350);
FORCEADD TP_TDR_4P_FTS..1
(700 1150);
FORCEPROP 1 LAST PART_NUMBER TP15
J 0
(575 1385);
DISPLAY 0.723404 (575 1385);
PAINT GREEN (575 1385);
DISPLAY INVISIBLE (575 1385);
FORCEPROP 1 LAST MATERIAL EMPTY
J 0
(575 1335);
DISPLAY 0.723404 (575 1335);
PAINT GREEN (575 1335);
FORCEPROP 2 LAST PACK_TYPE TH
J 0
(575 1475);
DISPLAY 1.021277 (575 1475);
FORCEPROP 2 LAST VALUE TP_TDR_4P_DIP
J 0
(575 1525);
DISPLAY 1.021277 (575 1525);
FORCEPROP 1 LAST $LOCATION X5
J 0
(575 1430);
DISPLAY 0.723404 (575 1430);
PAINT GREEN (575 1430);
FORCEPROP 0 LASTPIN (425 1225) $PN 2
J 2
(415 1235);
DISPLAY 0.680851 (415 1235);
PAINT MONO (415 1235);
FORCEPROP 0 LASTPIN (425 1075) $PN 3
J 2
(415 1085);
DISPLAY 0.680851 (415 1085);
PAINT MONO (415 1085);
FORCEPROP 0 LASTPIN (975 1225) $PN 1
J 0
(985 1235);
DISPLAY 0.680851 (985 1235);
PAINT MONO (985 1235);
FORCEPROP 0 LASTPIN (975 1075) $PN 4
J 0
(985 1085);
DISPLAY 0.680851 (985 1085);
PAINT MONO (985 1085);
FORCEPROP 1 LAST NEEDS_NO_SIZE TRUE
J 0
(700 1150);
DISPLAY 0.468085 (700 1150);
PAINT GREEN (700 1150);
DISPLAY INVISIBLE (700 1150);
FORCEPROP 2 LAST CDS_LIB pure_quanta
J 0
(700 1150);
DISPLAY INVISIBLE (700 1150);
FORCEPROP 1 LAST PATH I39
J 0
(800 1330);
DISPLAY 0.723404 (800 1330);
PAINT GREEN (800 1330);
DISPLAY INVISIBLE (800 1330);
FORCEPROP 0 LAST CDS_LOCATION X5
J 0
(575 1575);
DISPLAY 1.021277 (575 1575);
DISPLAY INVISIBLE (575 1575);
FORCEPROP 0 LAST $SEC 1
J 0
(575 1575);
DISPLAY 0.680851 (575 1575);
PAINT MONO (575 1575);
DISPLAY INVISIBLE (575 1575);
FORCEPROP 0 LAST CDS_SEC 1
J 0
(575 1575);
DISPLAY 1.021277 (575 1575);
DISPLAY INVISIBLE (575 1575);
FORCEADD TP_TDR_4P_FTS..1
R 4
(4725 3475);
FORCEPROP 1 LAST PART_NUMBER TP15
J 0
(4600 3815);
DISPLAY 0.723404 (4600 3815);
PAINT GREEN (4600 3815);
DISPLAY INVISIBLE (4600 3815);
FORCEPROP 2 LAST PACK_TYPE TH
J 0
(4600 3725);
DISPLAY 1.021277 (4600 3725);
FORCEPROP 1 LAST MATERIAL EMPTY
J 0
(4600 3865);
DISPLAY 0.723404 (4600 3865);
PAINT GREEN (4600 3865);
FORCEPROP 2 LAST VALUE TP_TDR_4P_DIP
J 0
(4600 3675);
DISPLAY 1.021277 (4600 3675);
FORCEPROP 1 LAST $LOCATION X20
J 0
(4600 3770);
DISPLAY 0.723404 (4600 3770);
PAINT GREEN (4600 3770);
FORCEPROP 0 LASTPIN (5000 3400) $PN 2
J 0
(5010 3410);
DISPLAY 0.680851 (5010 3410);
PAINT MONO (5010 3410);
FORCEPROP 0 LASTPIN (5000 3550) $PN 3
J 0
(5010 3560);
DISPLAY 0.680851 (5010 3560);
PAINT MONO (5010 3560);
FORCEPROP 0 LASTPIN (4450 3400) $PN 1
J 2
(4440 3410);
DISPLAY 0.680851 (4440 3410);
PAINT MONO (4440 3410);
FORCEPROP 0 LASTPIN (4450 3550) $PN 4
J 2
(4440 3560);
DISPLAY 0.680851 (4440 3560);
PAINT MONO (4440 3560);
FORCEPROP 1 LAST NEEDS_NO_SIZE TRUE
R 2
J 0
(4725 3475);
DISPLAY 0.468085 (4725 3475);
PAINT GREEN (4725 3475);
DISPLAY INVISIBLE (4725 3475);
FORCEPROP 2 LAST CDS_LIB pure_quanta
R 2
J 0
(4725 3475);
DISPLAY INVISIBLE (4725 3475);
FORCEPROP 1 LAST PATH I4
R 2
J 0
(4625 3295);
DISPLAY 0.723404 (4625 3295);
PAINT GREEN (4625 3295);
DISPLAY INVISIBLE (4625 3295);
FORCEPROP 0 LAST CDS_LOCATION X20
J 0
(4600 3900);
DISPLAY 1.021277 (4600 3900);
DISPLAY INVISIBLE (4600 3900);
FORCEPROP 0 LAST $SEC 1
J 0
(4600 3900);
DISPLAY 0.680851 (4600 3900);
PAINT MONO (4600 3900);
DISPLAY INVISIBLE (4600 3900);
FORCEPROP 0 LAST CDS_SEC 1
J 0
(4600 3900);
DISPLAY 1.021277 (4600 3900);
DISPLAY INVISIBLE (4600 3900);
FORCEADD TP_TDR_4P_FTS..1
R 4
(4700 -950);
FORCEPROP 1 LAST PART_NUMBER TP15
J 0
(4575 -610);
DISPLAY 0.723404 (4575 -610);
PAINT GREEN (4575 -610);
DISPLAY INVISIBLE (4575 -610);
FORCEPROP 2 LAST VALUE TP_TDR_4P_DIP
J 0
(4575 -750);
DISPLAY 1.021277 (4575 -750);
FORCEPROP 2 LAST PACK_TYPE TH
J 0
(4575 -700);
DISPLAY 1.021277 (4575 -700);
FORCEPROP 1 LAST MATERIAL EMPTY
J 0
(4575 -560);
DISPLAY 0.723404 (4575 -560);
PAINT GREEN (4575 -560);
FORCEPROP 1 LAST $LOCATION X24
J 0
(4575 -655);
DISPLAY 0.723404 (4575 -655);
PAINT GREEN (4575 -655);
FORCEPROP 0 LASTPIN (4975 -1025) $PN 2
J 0
(4985 -1015);
DISPLAY 0.680851 (4985 -1015);
PAINT MONO (4985 -1015);
FORCEPROP 0 LASTPIN (4975 -875) $PN 3
J 0
(4985 -865);
DISPLAY 0.680851 (4985 -865);
PAINT MONO (4985 -865);
FORCEPROP 0 LASTPIN (4425 -1025) $PN 1
J 2
(4415 -1015);
DISPLAY 0.680851 (4415 -1015);
PAINT MONO (4415 -1015);
FORCEPROP 0 LASTPIN (4425 -875) $PN 4
J 2
(4415 -865);
DISPLAY 0.680851 (4415 -865);
PAINT MONO (4415 -865);
FORCEPROP 1 LAST NEEDS_NO_SIZE TRUE
R 2
J 0
(4700 -950);
DISPLAY 0.468085 (4700 -950);
PAINT GREEN (4700 -950);
DISPLAY INVISIBLE (4700 -950);
FORCEPROP 2 LAST CDS_LIB pure_quanta
R 2
J 0
(4700 -950);
DISPLAY INVISIBLE (4700 -950);
FORCEPROP 1 LAST PATH I42
R 2
J 0
(4600 -1130);
DISPLAY 0.723404 (4600 -1130);
PAINT GREEN (4600 -1130);
DISPLAY INVISIBLE (4600 -1130);
FORCEPROP 0 LAST CDS_LOCATION X24
J 0
(4575 -525);
DISPLAY 1.021277 (4575 -525);
DISPLAY INVISIBLE (4575 -525);
FORCEPROP 0 LAST $SEC 1
J 0
(4575 -525);
DISPLAY 0.680851 (4575 -525);
PAINT MONO (4575 -525);
DISPLAY INVISIBLE (4575 -525);
FORCEPROP 0 LAST CDS_SEC 1
J 0
(4575 -525);
DISPLAY 1.021277 (4575 -525);
DISPLAY INVISIBLE (4575 -525);
FORCEADD TP_TDR_4P_FTS..1
(3375 -950);
FORCEPROP 1 LAST PART_NUMBER TP15
J 0
(3250 -715);
DISPLAY 0.723404 (3250 -715);
PAINT GREEN (3250 -715);
DISPLAY INVISIBLE (3250 -715);
FORCEPROP 2 LAST PACK_TYPE TH
J 0
(3250 -625);
DISPLAY 1.021277 (3250 -625);
FORCEPROP 2 LAST VALUE TP_TDR_4P_DIP
J 0
(3250 -575);
DISPLAY 1.021277 (3250 -575);
FORCEPROP 1 LAST MATERIAL EMPTY
J 0
(3250 -765);
DISPLAY 0.723404 (3250 -765);
PAINT GREEN (3250 -765);
FORCEPROP 1 LAST $LOCATION X18
J 0
(3250 -670);
DISPLAY 0.723404 (3250 -670);
PAINT GREEN (3250 -670);
FORCEPROP 0 LASTPIN (3100 -875) $PN 2
J 2
(3090 -865);
DISPLAY 0.680851 (3090 -865);
PAINT MONO (3090 -865);
FORCEPROP 0 LASTPIN (3100 -1025) $PN 3
J 2
(3090 -1015);
DISPLAY 0.680851 (3090 -1015);
PAINT MONO (3090 -1015);
FORCEPROP 0 LASTPIN (3650 -875) $PN 1
J 0
(3660 -865);
DISPLAY 0.680851 (3660 -865);
PAINT MONO (3660 -865);
FORCEPROP 0 LASTPIN (3650 -1025) $PN 4
J 0
(3660 -1015);
DISPLAY 0.680851 (3660 -1015);
PAINT MONO (3660 -1015);
FORCEPROP 1 LAST NEEDS_NO_SIZE TRUE
J 0
(3375 -950);
DISPLAY 0.468085 (3375 -950);
PAINT GREEN (3375 -950);
DISPLAY INVISIBLE (3375 -950);
FORCEPROP 2 LAST CDS_LIB pure_quanta
J 0
(3375 -950);
DISPLAY INVISIBLE (3375 -950);
FORCEPROP 1 LAST PATH I43
J 0
(3475 -770);
DISPLAY 0.723404 (3475 -770);
PAINT GREEN (3475 -770);
DISPLAY INVISIBLE (3475 -770);
FORCEPROP 0 LAST CDS_LOCATION X18
J 0
(3250 -525);
DISPLAY 1.021277 (3250 -525);
DISPLAY INVISIBLE (3250 -525);
FORCEPROP 0 LAST $SEC 1
J 0
(3250 -525);
DISPLAY 0.680851 (3250 -525);
PAINT MONO (3250 -525);
DISPLAY INVISIBLE (3250 -525);
FORCEPROP 0 LAST CDS_SEC 1
J 0
(3250 -525);
DISPLAY 1.021277 (3250 -525);
DISPLAY INVISIBLE (3250 -525);
FORCEADD TP_TDR_4P_FTS..1
R 4
(2025 -950);
FORCEPROP 1 LAST PART_NUMBER TP15
J 0
(1900 -610);
DISPLAY 0.723404 (1900 -610);
PAINT GREEN (1900 -610);
DISPLAY INVISIBLE (1900 -610);
FORCEPROP 2 LAST PACK_TYPE TH
J 0
(1900 -700);
DISPLAY 1.021277 (1900 -700);
FORCEPROP 2 LAST VALUE TP_TDR_4P_DIP
J 0
(1900 -750);
DISPLAY 1.021277 (1900 -750);
FORCEPROP 1 LAST MATERIAL EMPTY
J 0
(1900 -560);
DISPLAY 0.723404 (1900 -560);
PAINT GREEN (1900 -560);
FORCEPROP 1 LAST $LOCATION X12
J 0
(1900 -655);
DISPLAY 0.723404 (1900 -655);
PAINT GREEN (1900 -655);
FORCEPROP 0 LASTPIN (2300 -1025) $PN 2
J 0
(2310 -1015);
DISPLAY 0.680851 (2310 -1015);
PAINT MONO (2310 -1015);
FORCEPROP 0 LASTPIN (2300 -875) $PN 3
J 0
(2310 -865);
DISPLAY 0.680851 (2310 -865);
PAINT MONO (2310 -865);
FORCEPROP 0 LASTPIN (1750 -1025) $PN 1
J 2
(1740 -1015);
DISPLAY 0.680851 (1740 -1015);
PAINT MONO (1740 -1015);
FORCEPROP 0 LASTPIN (1750 -875) $PN 4
J 2
(1740 -865);
DISPLAY 0.680851 (1740 -865);
PAINT MONO (1740 -865);
FORCEPROP 1 LAST PATH I46
R 2
J 0
(1925 -1130);
DISPLAY 0.723404 (1925 -1130);
PAINT GREEN (1925 -1130);
DISPLAY INVISIBLE (1925 -1130);
FORCEPROP 1 LAST NEEDS_NO_SIZE TRUE
R 2
J 0
(2025 -950);
DISPLAY 0.468085 (2025 -950);
PAINT GREEN (2025 -950);
DISPLAY INVISIBLE (2025 -950);
FORCEPROP 2 LAST CDS_LIB pure_quanta
R 2
J 0
(2025 -950);
DISPLAY INVISIBLE (2025 -950);
FORCEPROP 0 LAST CDS_LOCATION X12
J 0
(1900 -525);
DISPLAY 1.021277 (1900 -525);
DISPLAY INVISIBLE (1900 -525);
FORCEPROP 0 LAST $SEC 1
J 0
(1900 -525);
DISPLAY 0.680851 (1900 -525);
PAINT MONO (1900 -525);
DISPLAY INVISIBLE (1900 -525);
FORCEPROP 0 LAST CDS_SEC 1
J 0
(1900 -525);
DISPLAY 1.021277 (1900 -525);
DISPLAY INVISIBLE (1900 -525);
FORCEADD TP_TDR_4P_FTS..1
(700 -950);
FORCEPROP 1 LAST PART_NUMBER TP15
J 0
(575 -715);
DISPLAY 0.723404 (575 -715);
PAINT GREEN (575 -715);
DISPLAY INVISIBLE (575 -715);
FORCEPROP 2 LAST PACK_TYPE TH
J 0
(575 -625);
DISPLAY 1.021277 (575 -625);
FORCEPROP 2 LAST VALUE TP_TDR_4P_DIP
J 0
(575 -575);
DISPLAY 1.021277 (575 -575);
FORCEPROP 1 LAST MATERIAL EMPTY
J 0
(575 -765);
DISPLAY 0.723404 (575 -765);
PAINT GREEN (575 -765);
FORCEPROP 1 LAST $LOCATION X6
J 0
(575 -670);
DISPLAY 0.723404 (575 -670);
PAINT GREEN (575 -670);
FORCEPROP 0 LASTPIN (425 -875) $PN 2
J 2
(415 -865);
DISPLAY 0.680851 (415 -865);
PAINT MONO (415 -865);
FORCEPROP 0 LASTPIN (425 -1025) $PN 3
J 2
(415 -1015);
DISPLAY 0.680851 (415 -1015);
PAINT MONO (415 -1015);
FORCEPROP 0 LASTPIN (975 -875) $PN 1
J 0
(985 -865);
DISPLAY 0.680851 (985 -865);
PAINT MONO (985 -865);
FORCEPROP 0 LASTPIN (975 -1025) $PN 4
J 0
(985 -1015);
DISPLAY 0.680851 (985 -1015);
PAINT MONO (985 -1015);
FORCEPROP 1 LAST PATH I47
J 0
(800 -770);
DISPLAY 0.723404 (800 -770);
PAINT GREEN (800 -770);
DISPLAY INVISIBLE (800 -770);
FORCEPROP 1 LAST NEEDS_NO_SIZE TRUE
J 0
(700 -950);
DISPLAY 0.468085 (700 -950);
PAINT GREEN (700 -950);
DISPLAY INVISIBLE (700 -950);
FORCEPROP 2 LAST CDS_LIB pure_quanta
J 0
(700 -950);
DISPLAY INVISIBLE (700 -950);
FORCEPROP 0 LAST CDS_LOCATION X6
J 0
(575 -525);
DISPLAY 1.021277 (575 -525);
DISPLAY INVISIBLE (575 -525);
FORCEPROP 0 LAST $SEC 1
J 0
(575 -525);
DISPLAY 0.680851 (575 -525);
PAINT MONO (575 -525);
DISPLAY INVISIBLE (575 -525);
FORCEPROP 0 LAST CDS_SEC 1
J 0
(575 -525);
DISPLAY 1.021277 (575 -525);
DISPLAY INVISIBLE (575 -525);
FORCEADD TDR_3P..2
(-1150 4275);
FORCEPROP 1 LAST PART_NUMBER N_A
J 1
(-1090 4125);
DISPLAY 0.872340 (-1090 4125);
PAINT PINK (-1090 4125);
DISPLAY INVISIBLE (-1090 4125);
FORCEPROP 1 LAST PACK_TYPE TH2
J 2
(-1125 4425);
DISPLAY 0.872340 (-1125 4425);
FORCEPROP 1 LAST $LOCATION DB7
J 2
(-1125 4475);
DISPLAY 0.872340 (-1125 4475);
PAINT PINK (-1125 4475);
FORCEPROP 0 LASTPIN (-1350 4275) $PN 1
J 2
(-1360 4285);
DISPLAY 0.680851 (-1360 4285);
PAINT MONO (-1360 4285);
FORCEPROP 0 LASTPIN (-1050 4325) $PN 2
J 0
(-1040 4335);
DISPLAY 0.680851 (-1040 4335);
PAINT MONO (-1040 4335);
FORCEPROP 0 LASTPIN (-1050 4225) $PN 3
J 0
(-1040 4235);
DISPLAY 0.680851 (-1040 4235);
PAINT MONO (-1040 4235);
FORCEPROP 1 LAST MATERIAL EMPTY
J 2
(-1150 4425);
DISPLAY 0.872340 (-1150 4425);
PAINT PINK (-1150 4425);
DISPLAY INVISIBLE (-1150 4425);
FORCEPROP 2 LAST CDS_LIB pure_quanta
J 0
(-1150 4275);
DISPLAY INVISIBLE (-1150 4275);
FORCEPROP 1 LAST CDS_LMAN_SYM_OUTLINE -150,100,50,-100
J 0
(-1150 4275);
DISPLAY 0.468085 (-1150 4275);
PAINT GREEN (-1150 4275);
DISPLAY INVISIBLE (-1150 4275);
FORCEPROP 1 LAST PATH I49
J 2
(-850 4425);
DISPLAY 0.872340 (-850 4425);
PAINT PINK (-850 4425);
DISPLAY INVISIBLE (-850 4425);
FORCEPROP 0 LAST CDS_LOCATION DB7
J 0
(-1125 4525);
DISPLAY 1.021277 (-1125 4525);
DISPLAY INVISIBLE (-1125 4525);
FORCEPROP 0 LAST $SEC 1
J 0
(-1125 4525);
DISPLAY 0.680851 (-1125 4525);
PAINT MONO (-1125 4525);
DISPLAY INVISIBLE (-1125 4525);
FORCEPROP 0 LAST CDS_SEC 1
J 0
(-1125 4525);
DISPLAY 1.021277 (-1125 4525);
DISPLAY INVISIBLE (-1125 4525);
FORCEADD UNIVERSAL_GND..1
(-1500 4050);
FORCEPROP 3 LASTPIN (-1500 4100) SIG_NAME T1_GND\g
J 0
(-1490 4110);
DISPLAY 0.659574 (-1490 4110);
PAINT MONO (-1490 4110);
DISPLAY INVISIBLE (-1490 4110);
FORCEPROP 1 LAST HDL_POWER T1_GND
J 1
(-1475 3975);
DISPLAY 0.872340 (-1475 3975);
PAINT GREEN (-1475 3975);
FORCEPROP 2 LAST CDS_LIB logical_power
J 0
(-1500 4050);
DISPLAY INVISIBLE (-1500 4050);
FORCEPROP 1 LAST PATH I50
J 0
(-1425 4050);
DISPLAY 0.872340 (-1425 4050);
PAINT AQUA (-1425 4050);
DISPLAY INVISIBLE (-1425 4050);
FORCEADD TDR_3P..2
(-1150 3750);
FORCEPROP 1 LAST PART_NUMBER N_A
J 1
(-1090 3600);
DISPLAY 0.872340 (-1090 3600);
PAINT PINK (-1090 3600);
DISPLAY INVISIBLE (-1090 3600);
FORCEPROP 1 LAST PACK_TYPE TH2
J 2
(-1125 3900);
DISPLAY 0.872340 (-1125 3900);
FORCEPROP 1 LAST $LOCATION DB8
J 2
(-1125 3950);
DISPLAY 0.872340 (-1125 3950);
PAINT PINK (-1125 3950);
FORCEPROP 0 LASTPIN (-1350 3750) $PN 1
J 2
(-1360 3760);
DISPLAY 0.680851 (-1360 3760);
PAINT MONO (-1360 3760);
FORCEPROP 0 LASTPIN (-1050 3800) $PN 2
J 0
(-1040 3810);
DISPLAY 0.680851 (-1040 3810);
PAINT MONO (-1040 3810);
FORCEPROP 0 LASTPIN (-1050 3700) $PN 3
J 0
(-1040 3710);
DISPLAY 0.680851 (-1040 3710);
PAINT MONO (-1040 3710);
FORCEPROP 1 LAST CDS_LMAN_SYM_OUTLINE -150,100,50,-100
J 0
(-1150 3750);
DISPLAY 0.468085 (-1150 3750);
PAINT GREEN (-1150 3750);
DISPLAY INVISIBLE (-1150 3750);
FORCEPROP 2 LAST CDS_LIB pure_quanta
J 0
(-1150 3750);
DISPLAY INVISIBLE (-1150 3750);
FORCEPROP 1 LAST MATERIAL EMPTY
J 2
(-1150 3900);
DISPLAY 0.872340 (-1150 3900);
PAINT PINK (-1150 3900);
DISPLAY INVISIBLE (-1150 3900);
FORCEPROP 1 LAST PATH I51
J 2
(-850 3900);
DISPLAY 0.872340 (-850 3900);
PAINT PINK (-850 3900);
DISPLAY INVISIBLE (-850 3900);
FORCEPROP 0 LAST CDS_LOCATION DB8
J 0
(-1125 4000);
DISPLAY 1.021277 (-1125 4000);
DISPLAY INVISIBLE (-1125 4000);
FORCEPROP 0 LAST $SEC 1
J 0
(-1125 4000);
DISPLAY 0.680851 (-1125 4000);
PAINT MONO (-1125 4000);
DISPLAY INVISIBLE (-1125 4000);
FORCEPROP 0 LAST CDS_SEC 1
J 0
(-1125 4000);
DISPLAY 1.021277 (-1125 4000);
DISPLAY INVISIBLE (-1125 4000);
FORCEADD UNIVERSAL_GND..1
(-1500 3525);
FORCEPROP 3 LASTPIN (-1500 3575) SIG_NAME T1_GND\g
J 0
(-1490 3585);
DISPLAY 0.659574 (-1490 3585);
PAINT MONO (-1490 3585);
DISPLAY INVISIBLE (-1490 3585);
FORCEPROP 1 LAST HDL_POWER T1_GND
J 1
(-1475 3450);
DISPLAY 0.872340 (-1475 3450);
PAINT GREEN (-1475 3450);
FORCEPROP 2 LAST CDS_LIB logical_power
J 0
(-1500 3525);
DISPLAY INVISIBLE (-1500 3525);
FORCEPROP 1 LAST PATH I52
J 0
(-1425 3525);
DISPLAY 0.872340 (-1425 3525);
PAINT AQUA (-1425 3525);
DISPLAY INVISIBLE (-1425 3525);
FORCEADD TDR_3P..2
(-1150 3225);
FORCEPROP 1 LAST PART_NUMBER N_A
J 1
(-1090 3075);
DISPLAY 0.872340 (-1090 3075);
PAINT PINK (-1090 3075);
DISPLAY INVISIBLE (-1090 3075);
FORCEPROP 1 LAST PACK_TYPE TH2
J 2
(-1125 3375);
DISPLAY 0.872340 (-1125 3375);
FORCEPROP 1 LAST $LOCATION DB9
J 2
(-1125 3425);
DISPLAY 0.872340 (-1125 3425);
PAINT PINK (-1125 3425);
FORCEPROP 0 LASTPIN (-1350 3225) $PN 1
J 2
(-1360 3235);
DISPLAY 0.680851 (-1360 3235);
PAINT MONO (-1360 3235);
FORCEPROP 0 LASTPIN (-1050 3275) $PN 2
J 0
(-1040 3285);
DISPLAY 0.680851 (-1040 3285);
PAINT MONO (-1040 3285);
FORCEPROP 0 LASTPIN (-1050 3175) $PN 3
J 0
(-1040 3185);
DISPLAY 0.680851 (-1040 3185);
PAINT MONO (-1040 3185);
FORCEPROP 1 LAST CDS_LMAN_SYM_OUTLINE -150,100,50,-100
J 0
(-1150 3225);
DISPLAY 0.468085 (-1150 3225);
PAINT GREEN (-1150 3225);
DISPLAY INVISIBLE (-1150 3225);
FORCEPROP 2 LAST CDS_LIB pure_quanta
J 0
(-1150 3225);
DISPLAY INVISIBLE (-1150 3225);
FORCEPROP 1 LAST MATERIAL EMPTY
J 2
(-1150 3375);
DISPLAY 0.872340 (-1150 3375);
PAINT PINK (-1150 3375);
DISPLAY INVISIBLE (-1150 3375);
FORCEPROP 1 LAST PATH I53
J 2
(-850 3375);
DISPLAY 0.872340 (-850 3375);
PAINT PINK (-850 3375);
DISPLAY INVISIBLE (-850 3375);
FORCEPROP 0 LAST CDS_LOCATION DB9
J 0
(-1125 3475);
DISPLAY 1.021277 (-1125 3475);
DISPLAY INVISIBLE (-1125 3475);
FORCEPROP 0 LAST $SEC 1
J 0
(-1125 3475);
DISPLAY 0.680851 (-1125 3475);
PAINT MONO (-1125 3475);
DISPLAY INVISIBLE (-1125 3475);
FORCEPROP 0 LAST CDS_SEC 1
J 0
(-1125 3475);
DISPLAY 1.021277 (-1125 3475);
DISPLAY INVISIBLE (-1125 3475);
FORCEADD UNIVERSAL_GND..1
(-1500 3000);
FORCEPROP 3 LASTPIN (-1500 3050) SIG_NAME T1_GND\g
J 0
(-1490 3060);
DISPLAY 0.659574 (-1490 3060);
PAINT MONO (-1490 3060);
DISPLAY INVISIBLE (-1490 3060);
FORCEPROP 1 LAST HDL_POWER T1_GND
J 1
(-1475 2925);
DISPLAY 0.872340 (-1475 2925);
PAINT GREEN (-1475 2925);
FORCEPROP 2 LAST CDS_LIB logical_power
J 0
(-1500 3000);
DISPLAY INVISIBLE (-1500 3000);
FORCEPROP 1 LAST PATH I54
J 0
(-1425 3000);
DISPLAY 0.872340 (-1425 3000);
PAINT AQUA (-1425 3000);
DISPLAY INVISIBLE (-1425 3000);
FORCEADD TDR_3P..2
(-1150 2700);
FORCEPROP 1 LAST PART_NUMBER N_A
J 1
(-1090 2550);
DISPLAY 0.872340 (-1090 2550);
PAINT PINK (-1090 2550);
DISPLAY INVISIBLE (-1090 2550);
FORCEPROP 1 LAST PACK_TYPE TH2
J 2
(-1125 2850);
DISPLAY 0.872340 (-1125 2850);
FORCEPROP 1 LAST $LOCATION DB10
J 2
(-1125 2900);
DISPLAY 0.872340 (-1125 2900);
PAINT PINK (-1125 2900);
FORCEPROP 0 LASTPIN (-1350 2700) $PN 1
J 2
(-1360 2710);
DISPLAY 0.680851 (-1360 2710);
PAINT MONO (-1360 2710);
FORCEPROP 0 LASTPIN (-1050 2750) $PN 2
J 0
(-1040 2760);
DISPLAY 0.680851 (-1040 2760);
PAINT MONO (-1040 2760);
FORCEPROP 0 LASTPIN (-1050 2650) $PN 3
J 0
(-1040 2660);
DISPLAY 0.680851 (-1040 2660);
PAINT MONO (-1040 2660);
FORCEPROP 1 LAST CDS_LMAN_SYM_OUTLINE -150,100,50,-100
J 0
(-1150 2700);
DISPLAY 0.468085 (-1150 2700);
PAINT GREEN (-1150 2700);
DISPLAY INVISIBLE (-1150 2700);
FORCEPROP 2 LAST CDS_LIB pure_quanta
J 0
(-1150 2700);
DISPLAY INVISIBLE (-1150 2700);
FORCEPROP 1 LAST MATERIAL EMPTY
J 2
(-1150 2850);
DISPLAY 0.872340 (-1150 2850);
PAINT PINK (-1150 2850);
DISPLAY INVISIBLE (-1150 2850);
FORCEPROP 1 LAST PATH I55
J 2
(-850 2850);
DISPLAY 0.872340 (-850 2850);
PAINT PINK (-850 2850);
DISPLAY INVISIBLE (-850 2850);
FORCEPROP 0 LAST CDS_LOCATION DB10
J 0
(-1125 2950);
DISPLAY 1.021277 (-1125 2950);
DISPLAY INVISIBLE (-1125 2950);
FORCEPROP 0 LAST $SEC 1
J 0
(-1125 2950);
DISPLAY 0.680851 (-1125 2950);
PAINT MONO (-1125 2950);
DISPLAY INVISIBLE (-1125 2950);
FORCEPROP 0 LAST CDS_SEC 1
J 0
(-1125 2950);
DISPLAY 1.021277 (-1125 2950);
DISPLAY INVISIBLE (-1125 2950);
FORCEADD UNIVERSAL_GND..1
(-1500 2475);
FORCEPROP 3 LASTPIN (-1500 2525) SIG_NAME T1_GND\g
J 0
(-1490 2535);
DISPLAY 0.659574 (-1490 2535);
PAINT MONO (-1490 2535);
DISPLAY INVISIBLE (-1490 2535);
FORCEPROP 1 LAST HDL_POWER T1_GND
J 1
(-1475 2400);
DISPLAY 0.872340 (-1475 2400);
PAINT GREEN (-1475 2400);
FORCEPROP 2 LAST CDS_LIB logical_power
J 0
(-1500 2475);
DISPLAY INVISIBLE (-1500 2475);
FORCEPROP 1 LAST PATH I56
J 0
(-1425 2475);
DISPLAY 0.872340 (-1425 2475);
PAINT AQUA (-1425 2475);
DISPLAY INVISIBLE (-1425 2475);
FORCEADD TDR_3P..2
(-1150 2175);
FORCEPROP 1 LAST PART_NUMBER N_A
J 1
(-1090 2025);
DISPLAY 0.872340 (-1090 2025);
PAINT PINK (-1090 2025);
DISPLAY INVISIBLE (-1090 2025);
FORCEPROP 1 LAST PACK_TYPE TH2
J 2
(-1125 2325);
DISPLAY 0.872340 (-1125 2325);
FORCEPROP 1 LAST $LOCATION DB11
J 2
(-1125 2375);
DISPLAY 0.872340 (-1125 2375);
PAINT PINK (-1125 2375);
FORCEPROP 0 LASTPIN (-1350 2175) $PN 1
J 2
(-1360 2185);
DISPLAY 0.680851 (-1360 2185);
PAINT MONO (-1360 2185);
FORCEPROP 0 LASTPIN (-1050 2225) $PN 2
J 0
(-1040 2235);
DISPLAY 0.680851 (-1040 2235);
PAINT MONO (-1040 2235);
FORCEPROP 0 LASTPIN (-1050 2125) $PN 3
J 0
(-1040 2135);
DISPLAY 0.680851 (-1040 2135);
PAINT MONO (-1040 2135);
FORCEPROP 1 LAST MATERIAL EMPTY
J 2
(-1150 2325);
DISPLAY 0.872340 (-1150 2325);
PAINT PINK (-1150 2325);
DISPLAY INVISIBLE (-1150 2325);
FORCEPROP 2 LAST CDS_LIB pure_quanta
J 0
(-1150 2175);
DISPLAY INVISIBLE (-1150 2175);
FORCEPROP 1 LAST CDS_LMAN_SYM_OUTLINE -150,100,50,-100
J 0
(-1150 2175);
DISPLAY 0.468085 (-1150 2175);
PAINT GREEN (-1150 2175);
DISPLAY INVISIBLE (-1150 2175);
FORCEPROP 1 LAST PATH I57
J 2
(-850 2325);
DISPLAY 0.872340 (-850 2325);
PAINT PINK (-850 2325);
DISPLAY INVISIBLE (-850 2325);
FORCEPROP 0 LAST CDS_LOCATION DB11
J 0
(-1125 2425);
DISPLAY 1.021277 (-1125 2425);
DISPLAY INVISIBLE (-1125 2425);
FORCEPROP 0 LAST $SEC 1
J 0
(-1125 2425);
DISPLAY 0.680851 (-1125 2425);
PAINT MONO (-1125 2425);
DISPLAY INVISIBLE (-1125 2425);
FORCEPROP 0 LAST CDS_SEC 1
J 0
(-1125 2425);
DISPLAY 1.021277 (-1125 2425);
DISPLAY INVISIBLE (-1125 2425);
FORCEADD UNIVERSAL_GND..1
(-1500 1950);
FORCEPROP 3 LASTPIN (-1500 2000) SIG_NAME T1_GND\g
J 0
(-1490 2010);
DISPLAY 0.659574 (-1490 2010);
PAINT MONO (-1490 2010);
DISPLAY INVISIBLE (-1490 2010);
FORCEPROP 1 LAST HDL_POWER T1_GND
J 1
(-1475 1875);
DISPLAY 0.872340 (-1475 1875);
PAINT GREEN (-1475 1875);
FORCEPROP 2 LAST CDS_LIB logical_power
J 0
(-1500 1950);
DISPLAY INVISIBLE (-1500 1950);
FORCEPROP 1 LAST PATH I58
J 0
(-1425 1950);
DISPLAY 0.872340 (-1425 1950);
PAINT AQUA (-1425 1950);
DISPLAY INVISIBLE (-1425 1950);
FORCEADD UNIVERSAL_GND..1
(-1550 350);
FORCEPROP 3 LASTPIN (-1550 400) SIG_NAME T1_GND\g
J 0
(-1540 410);
DISPLAY 0.659574 (-1540 410);
PAINT MONO (-1540 410);
DISPLAY INVISIBLE (-1540 410);
FORCEPROP 1 LAST HDL_POWER T1_GND
J 1
(-1525 275);
DISPLAY 0.872340 (-1525 275);
PAINT GREEN (-1525 275);
FORCEPROP 1 LAST PATH I59
J 0
(-1475 350);
DISPLAY 0.872340 (-1475 350);
PAINT AQUA (-1475 350);
DISPLAY INVISIBLE (-1475 350);
FORCEPROP 2 LAST CDS_LIB logical_power
J 0
(-1550 350);
DISPLAY INVISIBLE (-1550 350);
FORCEADD TDR_3P..2
(-1200 575);
FORCEPROP 1 LAST PART_NUMBER N_A
J 1
(-1140 425);
DISPLAY 0.872340 (-1140 425);
PAINT PINK (-1140 425);
DISPLAY INVISIBLE (-1140 425);
FORCEPROP 1 LAST PACK_TYPE TH2
J 2
(-1175 725);
DISPLAY 0.872340 (-1175 725);
FORCEPROP 1 LAST $LOCATION DB12
J 2
(-1175 775);
DISPLAY 0.872340 (-1175 775);
PAINT PINK (-1175 775);
FORCEPROP 0 LASTPIN (-1400 575) $PN 1
J 2
(-1410 585);
DISPLAY 0.680851 (-1410 585);
PAINT MONO (-1410 585);
FORCEPROP 0 LASTPIN (-1100 625) $PN 2
J 0
(-1090 635);
DISPLAY 0.680851 (-1090 635);
PAINT MONO (-1090 635);
FORCEPROP 0 LASTPIN (-1100 525) $PN 3
J 0
(-1090 535);
DISPLAY 0.680851 (-1090 535);
PAINT MONO (-1090 535);
FORCEPROP 1 LAST PATH I60
J 2
(-900 725);
DISPLAY 0.872340 (-900 725);
PAINT PINK (-900 725);
DISPLAY INVISIBLE (-900 725);
FORCEPROP 1 LAST MATERIAL EMPTY
J 2
(-1200 725);
DISPLAY 0.872340 (-1200 725);
PAINT PINK (-1200 725);
DISPLAY INVISIBLE (-1200 725);
FORCEPROP 2 LAST CDS_LIB pure_quanta
J 0
(-1200 575);
DISPLAY INVISIBLE (-1200 575);
FORCEPROP 1 LAST CDS_LMAN_SYM_OUTLINE -150,100,50,-100
J 0
(-1200 575);
DISPLAY 0.468085 (-1200 575);
PAINT GREEN (-1200 575);
DISPLAY INVISIBLE (-1200 575);
FORCEPROP 0 LAST CDS_LOCATION DB12
J 0
(-1175 825);
DISPLAY 1.021277 (-1175 825);
DISPLAY INVISIBLE (-1175 825);
FORCEPROP 0 LAST $SEC 1
J 0
(-1175 825);
DISPLAY 0.680851 (-1175 825);
PAINT MONO (-1175 825);
DISPLAY INVISIBLE (-1175 825);
FORCEPROP 0 LAST CDS_SEC 1
J 0
(-1175 825);
DISPLAY 1.021277 (-1175 825);
DISPLAY INVISIBLE (-1175 825);
FORCEADD TDR_3P..2
(-2850 4275);
FORCEPROP 1 LAST PART_NUMBER N_A
J 1
(-2790 4125);
DISPLAY 0.872340 (-2790 4125);
PAINT PINK (-2790 4125);
DISPLAY INVISIBLE (-2790 4125);
FORCEPROP 1 LAST PACK_TYPE TH2
J 2
(-2825 4425);
DISPLAY 0.872340 (-2825 4425);
FORCEPROP 1 LAST $LOCATION DB1
J 2
(-2825 4475);
DISPLAY 0.872340 (-2825 4475);
PAINT PINK (-2825 4475);
FORCEPROP 0 LASTPIN (-3050 4275) $PN 1
J 2
(-3060 4285);
DISPLAY 0.680851 (-3060 4285);
PAINT MONO (-3060 4285);
FORCEPROP 0 LASTPIN (-2750 4325) $PN 2
J 0
(-2740 4335);
DISPLAY 0.680851 (-2740 4335);
PAINT MONO (-2740 4335);
FORCEPROP 0 LASTPIN (-2750 4225) $PN 3
J 0
(-2740 4235);
DISPLAY 0.680851 (-2740 4235);
PAINT MONO (-2740 4235);
FORCEPROP 1 LAST CDS_LMAN_SYM_OUTLINE -150,100,50,-100
J 0
(-2850 4275);
DISPLAY 0.468085 (-2850 4275);
PAINT GREEN (-2850 4275);
DISPLAY INVISIBLE (-2850 4275);
FORCEPROP 2 LAST CDS_LIB pure_quanta
J 0
(-2850 4275);
DISPLAY INVISIBLE (-2850 4275);
FORCEPROP 1 LAST MATERIAL EMPTY
J 2
(-2850 4425);
DISPLAY 0.872340 (-2850 4425);
PAINT PINK (-2850 4425);
DISPLAY INVISIBLE (-2850 4425);
FORCEPROP 1 LAST PATH I61
J 2
(-2550 4425);
DISPLAY 0.872340 (-2550 4425);
PAINT PINK (-2550 4425);
DISPLAY INVISIBLE (-2550 4425);
FORCEPROP 0 LAST CDS_LOCATION DB1
J 0
(-2825 4525);
DISPLAY 1.021277 (-2825 4525);
DISPLAY INVISIBLE (-2825 4525);
FORCEPROP 0 LAST $SEC 1
J 0
(-2825 4525);
DISPLAY 0.680851 (-2825 4525);
PAINT MONO (-2825 4525);
DISPLAY INVISIBLE (-2825 4525);
FORCEPROP 0 LAST CDS_SEC 1
J 0
(-2825 4525);
DISPLAY 1.021277 (-2825 4525);
DISPLAY INVISIBLE (-2825 4525);
FORCEADD TDR_3P..2
(-2850 3750);
FORCEPROP 1 LAST PART_NUMBER N_A
J 1
(-2790 3600);
DISPLAY 0.872340 (-2790 3600);
PAINT PINK (-2790 3600);
DISPLAY INVISIBLE (-2790 3600);
FORCEPROP 1 LAST PACK_TYPE TH2
J 2
(-2825 3900);
DISPLAY 0.872340 (-2825 3900);
FORCEPROP 1 LAST $LOCATION DB2
J 2
(-2825 3950);
DISPLAY 0.872340 (-2825 3950);
PAINT PINK (-2825 3950);
FORCEPROP 0 LASTPIN (-3050 3750) $PN 1
J 2
(-3060 3760);
DISPLAY 0.680851 (-3060 3760);
PAINT MONO (-3060 3760);
FORCEPROP 0 LASTPIN (-2750 3800) $PN 2
J 0
(-2740 3810);
DISPLAY 0.680851 (-2740 3810);
PAINT MONO (-2740 3810);
FORCEPROP 0 LASTPIN (-2750 3700) $PN 3
J 0
(-2740 3710);
DISPLAY 0.680851 (-2740 3710);
PAINT MONO (-2740 3710);
FORCEPROP 1 LAST MATERIAL EMPTY
J 2
(-2850 3900);
DISPLAY 0.872340 (-2850 3900);
PAINT PINK (-2850 3900);
DISPLAY INVISIBLE (-2850 3900);
FORCEPROP 2 LAST CDS_LIB pure_quanta
J 0
(-2850 3750);
DISPLAY INVISIBLE (-2850 3750);
FORCEPROP 1 LAST CDS_LMAN_SYM_OUTLINE -150,100,50,-100
J 0
(-2850 3750);
DISPLAY 0.468085 (-2850 3750);
PAINT GREEN (-2850 3750);
DISPLAY INVISIBLE (-2850 3750);
FORCEPROP 1 LAST PATH I62
J 2
(-2550 3900);
DISPLAY 0.872340 (-2550 3900);
PAINT PINK (-2550 3900);
DISPLAY INVISIBLE (-2550 3900);
FORCEPROP 0 LAST CDS_LOCATION DB2
J 0
(-2825 4000);
DISPLAY 1.021277 (-2825 4000);
DISPLAY INVISIBLE (-2825 4000);
FORCEPROP 0 LAST $SEC 1
J 0
(-2825 4000);
DISPLAY 0.680851 (-2825 4000);
PAINT MONO (-2825 4000);
DISPLAY INVISIBLE (-2825 4000);
FORCEPROP 0 LAST CDS_SEC 1
J 0
(-2825 4000);
DISPLAY 1.021277 (-2825 4000);
DISPLAY INVISIBLE (-2825 4000);
FORCEADD TDR_3P..2
(-2850 3225);
FORCEPROP 1 LAST PART_NUMBER N_A
J 1
(-2790 3075);
DISPLAY 0.872340 (-2790 3075);
PAINT PINK (-2790 3075);
DISPLAY INVISIBLE (-2790 3075);
FORCEPROP 1 LAST PACK_TYPE TH2
J 2
(-2825 3375);
DISPLAY 0.872340 (-2825 3375);
FORCEPROP 1 LAST $LOCATION DB3
J 2
(-2825 3425);
DISPLAY 0.872340 (-2825 3425);
PAINT PINK (-2825 3425);
FORCEPROP 0 LASTPIN (-3050 3225) $PN 1
J 2
(-3060 3235);
DISPLAY 0.680851 (-3060 3235);
PAINT MONO (-3060 3235);
FORCEPROP 0 LASTPIN (-2750 3275) $PN 2
J 0
(-2740 3285);
DISPLAY 0.680851 (-2740 3285);
PAINT MONO (-2740 3285);
FORCEPROP 0 LASTPIN (-2750 3175) $PN 3
J 0
(-2740 3185);
DISPLAY 0.680851 (-2740 3185);
PAINT MONO (-2740 3185);
FORCEPROP 1 LAST MATERIAL EMPTY
J 2
(-2850 3375);
DISPLAY 0.872340 (-2850 3375);
PAINT PINK (-2850 3375);
DISPLAY INVISIBLE (-2850 3375);
FORCEPROP 2 LAST CDS_LIB pure_quanta
J 0
(-2850 3225);
DISPLAY INVISIBLE (-2850 3225);
FORCEPROP 1 LAST CDS_LMAN_SYM_OUTLINE -150,100,50,-100
J 0
(-2850 3225);
DISPLAY 0.468085 (-2850 3225);
PAINT GREEN (-2850 3225);
DISPLAY INVISIBLE (-2850 3225);
FORCEPROP 1 LAST PATH I63
J 2
(-2550 3375);
DISPLAY 0.872340 (-2550 3375);
PAINT PINK (-2550 3375);
DISPLAY INVISIBLE (-2550 3375);
FORCEPROP 0 LAST CDS_LOCATION DB3
J 0
(-2825 3475);
DISPLAY 1.021277 (-2825 3475);
DISPLAY INVISIBLE (-2825 3475);
FORCEPROP 0 LAST $SEC 1
J 0
(-2825 3475);
DISPLAY 0.680851 (-2825 3475);
PAINT MONO (-2825 3475);
DISPLAY INVISIBLE (-2825 3475);
FORCEPROP 0 LAST CDS_SEC 1
J 0
(-2825 3475);
DISPLAY 1.021277 (-2825 3475);
DISPLAY INVISIBLE (-2825 3475);
FORCEADD UNIVERSAL_GND..1
(-3200 4050);
FORCEPROP 3 LASTPIN (-3200 4100) SIG_NAME T1_GND\g
J 0
(-3190 4110);
DISPLAY 0.659574 (-3190 4110);
PAINT MONO (-3190 4110);
DISPLAY INVISIBLE (-3190 4110);
FORCEPROP 1 LAST HDL_POWER T1_GND
J 1
(-3175 3975);
DISPLAY 0.872340 (-3175 3975);
PAINT GREEN (-3175 3975);
FORCEPROP 2 LAST CDS_LIB logical_power
J 0
(-3200 4050);
DISPLAY INVISIBLE (-3200 4050);
FORCEPROP 1 LAST PATH I64
J 0
(-3125 4050);
DISPLAY 0.872340 (-3125 4050);
PAINT AQUA (-3125 4050);
DISPLAY INVISIBLE (-3125 4050);
FORCEADD UNIVERSAL_GND..1
(-3200 3525);
FORCEPROP 3 LASTPIN (-3200 3575) SIG_NAME T1_GND\g
J 0
(-3190 3585);
DISPLAY 0.659574 (-3190 3585);
PAINT MONO (-3190 3585);
DISPLAY INVISIBLE (-3190 3585);
FORCEPROP 1 LAST HDL_POWER T1_GND
J 1
(-3175 3450);
DISPLAY 0.872340 (-3175 3450);
PAINT GREEN (-3175 3450);
FORCEPROP 2 LAST CDS_LIB logical_power
J 0
(-3200 3525);
DISPLAY INVISIBLE (-3200 3525);
FORCEPROP 1 LAST PATH I65
J 0
(-3125 3525);
DISPLAY 0.872340 (-3125 3525);
PAINT AQUA (-3125 3525);
DISPLAY INVISIBLE (-3125 3525);
FORCEADD UNIVERSAL_GND..1
(-3200 3000);
FORCEPROP 3 LASTPIN (-3200 3050) SIG_NAME T1_GND\g
J 0
(-3190 3060);
DISPLAY 0.659574 (-3190 3060);
PAINT MONO (-3190 3060);
DISPLAY INVISIBLE (-3190 3060);
FORCEPROP 1 LAST HDL_POWER T1_GND
J 1
(-3175 2925);
DISPLAY 0.872340 (-3175 2925);
PAINT GREEN (-3175 2925);
FORCEPROP 2 LAST CDS_LIB logical_power
J 0
(-3200 3000);
DISPLAY INVISIBLE (-3200 3000);
FORCEPROP 1 LAST PATH I66
J 0
(-3125 3000);
DISPLAY 0.872340 (-3125 3000);
PAINT AQUA (-3125 3000);
DISPLAY INVISIBLE (-3125 3000);
FORCEADD TDR_3P..2
(-2850 2700);
FORCEPROP 1 LAST PART_NUMBER N_A
J 1
(-2790 2550);
DISPLAY 0.872340 (-2790 2550);
PAINT PINK (-2790 2550);
DISPLAY INVISIBLE (-2790 2550);
FORCEPROP 1 LAST PACK_TYPE TH2
J 2
(-2825 2850);
DISPLAY 0.872340 (-2825 2850);
FORCEPROP 1 LAST $LOCATION DB4
J 2
(-2825 2900);
DISPLAY 0.872340 (-2825 2900);
PAINT PINK (-2825 2900);
FORCEPROP 0 LASTPIN (-3050 2700) $PN 1
J 2
(-3060 2710);
DISPLAY 0.680851 (-3060 2710);
PAINT MONO (-3060 2710);
FORCEPROP 0 LASTPIN (-2750 2750) $PN 2
J 0
(-2740 2760);
DISPLAY 0.680851 (-2740 2760);
PAINT MONO (-2740 2760);
FORCEPROP 0 LASTPIN (-2750 2650) $PN 3
J 0
(-2740 2660);
DISPLAY 0.680851 (-2740 2660);
PAINT MONO (-2740 2660);
FORCEPROP 1 LAST MATERIAL EMPTY
J 2
(-2850 2850);
DISPLAY 0.872340 (-2850 2850);
PAINT PINK (-2850 2850);
DISPLAY INVISIBLE (-2850 2850);
FORCEPROP 2 LAST CDS_LIB pure_quanta
J 0
(-2850 2700);
DISPLAY INVISIBLE (-2850 2700);
FORCEPROP 1 LAST CDS_LMAN_SYM_OUTLINE -150,100,50,-100
J 0
(-2850 2700);
DISPLAY 0.468085 (-2850 2700);
PAINT GREEN (-2850 2700);
DISPLAY INVISIBLE (-2850 2700);
FORCEPROP 1 LAST PATH I67
J 2
(-2550 2850);
DISPLAY 0.872340 (-2550 2850);
PAINT PINK (-2550 2850);
DISPLAY INVISIBLE (-2550 2850);
FORCEPROP 0 LAST CDS_LOCATION DB4
J 0
(-2825 2950);
DISPLAY 1.021277 (-2825 2950);
DISPLAY INVISIBLE (-2825 2950);
FORCEPROP 0 LAST $SEC 1
J 0
(-2825 2950);
DISPLAY 0.680851 (-2825 2950);
PAINT MONO (-2825 2950);
DISPLAY INVISIBLE (-2825 2950);
FORCEPROP 0 LAST CDS_SEC 1
J 0
(-2825 2950);
DISPLAY 1.021277 (-2825 2950);
DISPLAY INVISIBLE (-2825 2950);
FORCEADD TDR_3P..2
(-2850 2175);
FORCEPROP 1 LAST PART_NUMBER N_A
J 1
(-2790 2025);
DISPLAY 0.872340 (-2790 2025);
PAINT PINK (-2790 2025);
DISPLAY INVISIBLE (-2790 2025);
FORCEPROP 1 LAST PACK_TYPE TH2
J 2
(-2825 2325);
DISPLAY 0.872340 (-2825 2325);
FORCEPROP 1 LAST $LOCATION DB5
J 2
(-2825 2375);
DISPLAY 0.872340 (-2825 2375);
PAINT PINK (-2825 2375);
FORCEPROP 0 LASTPIN (-3050 2175) $PN 1
J 2
(-3060 2185);
DISPLAY 0.680851 (-3060 2185);
PAINT MONO (-3060 2185);
FORCEPROP 0 LASTPIN (-2750 2225) $PN 2
J 0
(-2740 2235);
DISPLAY 0.680851 (-2740 2235);
PAINT MONO (-2740 2235);
FORCEPROP 0 LASTPIN (-2750 2125) $PN 3
J 0
(-2740 2135);
DISPLAY 0.680851 (-2740 2135);
PAINT MONO (-2740 2135);
FORCEPROP 1 LAST CDS_LMAN_SYM_OUTLINE -150,100,50,-100
J 0
(-2850 2175);
DISPLAY 0.468085 (-2850 2175);
PAINT GREEN (-2850 2175);
DISPLAY INVISIBLE (-2850 2175);
FORCEPROP 2 LAST CDS_LIB pure_quanta
J 0
(-2850 2175);
DISPLAY INVISIBLE (-2850 2175);
FORCEPROP 1 LAST MATERIAL EMPTY
J 2
(-2850 2325);
DISPLAY 0.872340 (-2850 2325);
PAINT PINK (-2850 2325);
DISPLAY INVISIBLE (-2850 2325);
FORCEPROP 1 LAST PATH I68
J 2
(-2550 2325);
DISPLAY 0.872340 (-2550 2325);
PAINT PINK (-2550 2325);
DISPLAY INVISIBLE (-2550 2325);
FORCEPROP 0 LAST CDS_LOCATION DB5
J 0
(-2825 2425);
DISPLAY 1.021277 (-2825 2425);
DISPLAY INVISIBLE (-2825 2425);
FORCEPROP 0 LAST $SEC 1
J 0
(-2825 2425);
DISPLAY 0.680851 (-2825 2425);
PAINT MONO (-2825 2425);
DISPLAY INVISIBLE (-2825 2425);
FORCEPROP 0 LAST CDS_SEC 1
J 0
(-2825 2425);
DISPLAY 1.021277 (-2825 2425);
DISPLAY INVISIBLE (-2825 2425);
FORCEADD TDR_3P..2
(-2900 575);
FORCEPROP 1 LAST PART_NUMBER N_A
J 1
(-2840 425);
DISPLAY 0.872340 (-2840 425);
PAINT PINK (-2840 425);
DISPLAY INVISIBLE (-2840 425);
FORCEPROP 1 LAST PACK_TYPE TH2
J 2
(-2875 725);
DISPLAY 0.872340 (-2875 725);
FORCEPROP 1 LAST $LOCATION DB6
J 2
(-2875 775);
DISPLAY 0.872340 (-2875 775);
PAINT PINK (-2875 775);
FORCEPROP 0 LASTPIN (-3100 575) $PN 1
J 2
(-3110 585);
DISPLAY 0.680851 (-3110 585);
PAINT MONO (-3110 585);
FORCEPROP 0 LASTPIN (-2800 625) $PN 2
J 0
(-2790 635);
DISPLAY 0.680851 (-2790 635);
PAINT MONO (-2790 635);
FORCEPROP 0 LASTPIN (-2800 525) $PN 3
J 0
(-2790 535);
DISPLAY 0.680851 (-2790 535);
PAINT MONO (-2790 535);
FORCEPROP 1 LAST PATH I69
J 2
(-2600 725);
DISPLAY 0.872340 (-2600 725);
PAINT PINK (-2600 725);
DISPLAY INVISIBLE (-2600 725);
FORCEPROP 1 LAST CDS_LMAN_SYM_OUTLINE -150,100,50,-100
J 0
(-2900 575);
DISPLAY 0.468085 (-2900 575);
PAINT GREEN (-2900 575);
DISPLAY INVISIBLE (-2900 575);
FORCEPROP 2 LAST CDS_LIB pure_quanta
J 0
(-2900 575);
DISPLAY INVISIBLE (-2900 575);
FORCEPROP 1 LAST MATERIAL EMPTY
J 2
(-2900 725);
DISPLAY 0.872340 (-2900 725);
PAINT PINK (-2900 725);
DISPLAY INVISIBLE (-2900 725);
FORCEPROP 0 LAST CDS_LOCATION DB6
J 0
(-2875 825);
DISPLAY 1.021277 (-2875 825);
DISPLAY INVISIBLE (-2875 825);
FORCEPROP 0 LAST $SEC 1
J 0
(-2875 825);
DISPLAY 0.680851 (-2875 825);
PAINT MONO (-2875 825);
DISPLAY INVISIBLE (-2875 825);
FORCEPROP 0 LAST CDS_SEC 1
J 0
(-2875 825);
DISPLAY 1.021277 (-2875 825);
DISPLAY INVISIBLE (-2875 825);
FORCEADD UNIVERSAL_GND..1
(-3200 2475);
FORCEPROP 3 LASTPIN (-3200 2525) SIG_NAME T1_GND\g
J 0
(-3190 2535);
DISPLAY 0.659574 (-3190 2535);
PAINT MONO (-3190 2535);
DISPLAY INVISIBLE (-3190 2535);
FORCEPROP 1 LAST HDL_POWER T1_GND
J 1
(-3175 2400);
DISPLAY 0.872340 (-3175 2400);
PAINT GREEN (-3175 2400);
FORCEPROP 2 LAST CDS_LIB logical_power
J 0
(-3200 2475);
DISPLAY INVISIBLE (-3200 2475);
FORCEPROP 1 LAST PATH I70
J 0
(-3125 2475);
DISPLAY 0.872340 (-3125 2475);
PAINT AQUA (-3125 2475);
DISPLAY INVISIBLE (-3125 2475);
FORCEADD UNIVERSAL_GND..1
(-3200 1950);
FORCEPROP 3 LASTPIN (-3200 2000) SIG_NAME T1_GND\g
J 0
(-3190 2010);
DISPLAY 0.659574 (-3190 2010);
PAINT MONO (-3190 2010);
DISPLAY INVISIBLE (-3190 2010);
FORCEPROP 1 LAST HDL_POWER T1_GND
J 1
(-3175 1875);
DISPLAY 0.872340 (-3175 1875);
PAINT GREEN (-3175 1875);
FORCEPROP 2 LAST CDS_LIB logical_power
J 0
(-3200 1950);
DISPLAY INVISIBLE (-3200 1950);
FORCEPROP 1 LAST PATH I71
J 0
(-3125 1950);
DISPLAY 0.872340 (-3125 1950);
PAINT AQUA (-3125 1950);
DISPLAY INVISIBLE (-3125 1950);
FORCEADD UNIVERSAL_GND..1
(-3250 350);
FORCEPROP 3 LASTPIN (-3250 400) SIG_NAME T1_GND\g
J 0
(-3240 410);
DISPLAY 0.659574 (-3240 410);
PAINT MONO (-3240 410);
DISPLAY INVISIBLE (-3240 410);
FORCEPROP 1 LAST HDL_POWER T1_GND
J 1
(-3225 275);
DISPLAY 0.872340 (-3225 275);
PAINT GREEN (-3225 275);
FORCEPROP 1 LAST PATH I72
J 0
(-3175 350);
DISPLAY 0.872340 (-3175 350);
PAINT AQUA (-3175 350);
DISPLAY INVISIBLE (-3175 350);
FORCEPROP 2 LAST CDS_LIB logical_power
J 0
(-3250 350);
DISPLAY INVISIBLE (-3250 350);
FORCEADD UNIVERSAL_GND..1
(5125 4025);
FORCEPROP 3 LASTPIN (5125 4075) SIG_NAME T1_GND\g
J 0
(5135 4085);
DISPLAY 0.659574 (5135 4085);
PAINT MONO (5135 4085);
DISPLAY INVISIBLE (5135 4085);
FORCEPROP 1 LAST HDL_POWER T1_GND
J 1
(5150 3950);
DISPLAY 0.872340 (5150 3950);
PAINT GREEN (5150 3950);
FORCEPROP 2 LAST CDS_LIB logical_power
J 0
(5125 4025);
DISPLAY INVISIBLE (5125 4025);
FORCEPROP 1 LAST PATH I73
J 0
(5200 4025);
DISPLAY 0.872340 (5200 4025);
PAINT AQUA (5200 4025);
DISPLAY INVISIBLE (5200 4025);
FORCEADD UNIVERSAL_GND..1
(5125 3250);
FORCEPROP 3 LASTPIN (5125 3300) SIG_NAME T1_GND\g
J 0
(5135 3310);
DISPLAY 0.659574 (5135 3310);
PAINT MONO (5135 3310);
DISPLAY INVISIBLE (5135 3310);
FORCEPROP 1 LAST HDL_POWER T1_GND
J 1
(5150 3175);
DISPLAY 0.872340 (5150 3175);
PAINT GREEN (5150 3175);
FORCEPROP 2 LAST CDS_LIB logical_power
J 0
(5125 3250);
DISPLAY INVISIBLE (5125 3250);
FORCEPROP 1 LAST PATH I74
J 0
(5200 3250);
DISPLAY 0.872340 (5200 3250);
PAINT AQUA (5200 3250);
DISPLAY INVISIBLE (5200 3250);
FORCEADD UNIVERSAL_GND..1
(5125 2475);
FORCEPROP 3 LASTPIN (5125 2525) SIG_NAME T1_GND\g
J 0
(5135 2535);
DISPLAY 0.659574 (5135 2535);
PAINT MONO (5135 2535);
DISPLAY INVISIBLE (5135 2535);
FORCEPROP 1 LAST HDL_POWER T1_GND
J 1
(5150 2400);
DISPLAY 0.872340 (5150 2400);
PAINT GREEN (5150 2400);
FORCEPROP 1 LAST PATH I75
J 0
(5200 2475);
DISPLAY 0.872340 (5200 2475);
PAINT AQUA (5200 2475);
DISPLAY INVISIBLE (5200 2475);
FORCEPROP 2 LAST CDS_LIB logical_power
J 0
(5125 2475);
DISPLAY INVISIBLE (5125 2475);
FORCEADD UNIVERSAL_GND..1
(5125 1700);
FORCEPROP 3 LASTPIN (5125 1750) SIG_NAME T1_GND\g
J 0
(5135 1760);
DISPLAY 0.659574 (5135 1760);
PAINT MONO (5135 1760);
DISPLAY INVISIBLE (5135 1760);
FORCEPROP 1 LAST HDL_POWER T1_GND
J 1
(5150 1625);
DISPLAY 0.872340 (5150 1625);
PAINT GREEN (5150 1625);
FORCEPROP 1 LAST PATH I76
J 0
(5200 1700);
DISPLAY 0.872340 (5200 1700);
PAINT AQUA (5200 1700);
DISPLAY INVISIBLE (5200 1700);
FORCEPROP 2 LAST CDS_LIB logical_power
J 0
(5125 1700);
DISPLAY INVISIBLE (5125 1700);
FORCEADD UNIVERSAL_GND..1
(5125 925);
FORCEPROP 3 LASTPIN (5125 975) SIG_NAME T1_GND\g
J 0
(5135 985);
DISPLAY 0.659574 (5135 985);
PAINT MONO (5135 985);
DISPLAY INVISIBLE (5135 985);
FORCEPROP 1 LAST HDL_POWER T1_GND
J 1
(5150 850);
DISPLAY 0.872340 (5150 850);
PAINT GREEN (5150 850);
FORCEPROP 1 LAST PATH I77
J 0
(5200 925);
DISPLAY 0.872340 (5200 925);
PAINT AQUA (5200 925);
DISPLAY INVISIBLE (5200 925);
FORCEPROP 2 LAST CDS_LIB logical_power
J 0
(5125 925);
DISPLAY INVISIBLE (5125 925);
FORCEADD UNIVERSAL_GND..1
(5100 -1150);
FORCEPROP 3 LASTPIN (5100 -1100) SIG_NAME T1_GND\g
J 0
(5110 -1090);
DISPLAY 0.659574 (5110 -1090);
PAINT MONO (5110 -1090);
DISPLAY INVISIBLE (5110 -1090);
FORCEPROP 1 LAST HDL_POWER T1_GND
J 1
(5125 -1225);
DISPLAY 0.872340 (5125 -1225);
PAINT GREEN (5125 -1225);
FORCEPROP 1 LAST PATH I78
J 0
(5175 -1150);
DISPLAY 0.872340 (5175 -1150);
PAINT AQUA (5175 -1150);
DISPLAY INVISIBLE (5175 -1150);
FORCEPROP 2 LAST CDS_LIB logical_power
J 0
(5100 -1150);
DISPLAY INVISIBLE (5100 -1150);
FORCEADD UNIVERSAL_GND..1
(2975 3250);
FORCEPROP 3 LASTPIN (2975 3300) SIG_NAME T1_GND\g
J 0
(2985 3310);
DISPLAY 0.659574 (2985 3310);
PAINT MONO (2985 3310);
DISPLAY INVISIBLE (2985 3310);
FORCEPROP 1 LAST HDL_POWER T1_GND
J 1
(3000 3175);
DISPLAY 0.872340 (3000 3175);
PAINT GREEN (3000 3175);
FORCEPROP 2 LAST CDS_LIB logical_power
J 0
(2975 3250);
DISPLAY INVISIBLE (2975 3250);
FORCEPROP 1 LAST PATH I79
J 0
(3050 3250);
DISPLAY 0.872340 (3050 3250);
PAINT AQUA (3050 3250);
DISPLAY INVISIBLE (3050 3250);
FORCEADD TP_TDR_4P_FTS..1
R 4
(4725 1925);
FORCEPROP 1 LAST PART_NUMBER TP15
J 0
(4600 2265);
DISPLAY 0.723404 (4600 2265);
PAINT GREEN (4600 2265);
DISPLAY INVISIBLE (4600 2265);
FORCEPROP 1 LAST MATERIAL EMPTY
J 0
(4600 2315);
DISPLAY 0.723404 (4600 2315);
PAINT GREEN (4600 2315);
FORCEPROP 2 LAST VALUE TP_TDR_4P_DIP
J 0
(4600 2125);
DISPLAY 1.021277 (4600 2125);
FORCEPROP 2 LAST PACK_TYPE TH
J 0
(4600 2175);
DISPLAY 1.021277 (4600 2175);
FORCEPROP 1 LAST $LOCATION X22
J 0
(4600 2220);
DISPLAY 0.723404 (4600 2220);
PAINT GREEN (4600 2220);
FORCEPROP 0 LASTPIN (5000 1850) $PN 2
J 0
(5010 1860);
DISPLAY 0.680851 (5010 1860);
PAINT MONO (5010 1860);
FORCEPROP 0 LASTPIN (5000 2000) $PN 3
J 0
(5010 2010);
DISPLAY 0.680851 (5010 2010);
PAINT MONO (5010 2010);
FORCEPROP 0 LASTPIN (4450 1850) $PN 1
J 2
(4440 1860);
DISPLAY 0.680851 (4440 1860);
PAINT MONO (4440 1860);
FORCEPROP 0 LASTPIN (4450 2000) $PN 4
J 2
(4440 2010);
DISPLAY 0.680851 (4440 2010);
PAINT MONO (4440 2010);
FORCEPROP 1 LAST PATH I8
R 2
J 0
(4625 1745);
DISPLAY 0.723404 (4625 1745);
PAINT GREEN (4625 1745);
DISPLAY INVISIBLE (4625 1745);
FORCEPROP 1 LAST NEEDS_NO_SIZE TRUE
R 2
J 0
(4725 1925);
DISPLAY 0.468085 (4725 1925);
PAINT GREEN (4725 1925);
DISPLAY INVISIBLE (4725 1925);
FORCEPROP 2 LAST CDS_LIB pure_quanta
R 2
J 0
(4725 1925);
DISPLAY INVISIBLE (4725 1925);
FORCEPROP 0 LAST CDS_LOCATION X22
J 0
(4600 2350);
DISPLAY 1.021277 (4600 2350);
DISPLAY INVISIBLE (4600 2350);
FORCEPROP 0 LAST $SEC 1
J 0
(4600 2350);
DISPLAY 0.680851 (4600 2350);
PAINT MONO (4600 2350);
DISPLAY INVISIBLE (4600 2350);
FORCEPROP 0 LAST CDS_SEC 1
J 0
(4600 2350);
DISPLAY 1.021277 (4600 2350);
DISPLAY INVISIBLE (4600 2350);
FORCEADD UNIVERSAL_GND..1
(2975 2475);
FORCEPROP 3 LASTPIN (2975 2525) SIG_NAME T1_GND\g
J 0
(2985 2535);
DISPLAY 0.659574 (2985 2535);
PAINT MONO (2985 2535);
DISPLAY INVISIBLE (2985 2535);
FORCEPROP 1 LAST HDL_POWER T1_GND
J 1
(3000 2400);
DISPLAY 0.872340 (3000 2400);
PAINT GREEN (3000 2400);
FORCEPROP 1 LAST PATH I80
J 0
(3050 2475);
DISPLAY 0.872340 (3050 2475);
PAINT AQUA (3050 2475);
DISPLAY INVISIBLE (3050 2475);
FORCEPROP 2 LAST CDS_LIB logical_power
J 0
(2975 2475);
DISPLAY INVISIBLE (2975 2475);
FORCEADD UNIVERSAL_GND..1
(2975 1700);
FORCEPROP 3 LASTPIN (2975 1750) SIG_NAME T1_GND\g
J 0
(2985 1760);
DISPLAY 0.659574 (2985 1760);
PAINT MONO (2985 1760);
DISPLAY INVISIBLE (2985 1760);
FORCEPROP 1 LAST HDL_POWER T1_GND
J 1
(3000 1625);
DISPLAY 0.872340 (3000 1625);
PAINT GREEN (3000 1625);
FORCEPROP 1 LAST PATH I81
J 0
(3050 1700);
DISPLAY 0.872340 (3050 1700);
PAINT AQUA (3050 1700);
DISPLAY INVISIBLE (3050 1700);
FORCEPROP 2 LAST CDS_LIB logical_power
J 0
(2975 1700);
DISPLAY INVISIBLE (2975 1700);
FORCEADD UNIVERSAL_GND..1
(2975 925);
FORCEPROP 3 LASTPIN (2975 975) SIG_NAME T1_GND\g
J 0
(2985 985);
DISPLAY 0.659574 (2985 985);
PAINT MONO (2985 985);
DISPLAY INVISIBLE (2985 985);
FORCEPROP 1 LAST HDL_POWER T1_GND
J 1
(3000 850);
DISPLAY 0.872340 (3000 850);
PAINT GREEN (3000 850);
FORCEPROP 1 LAST PATH I82
J 0
(3050 925);
DISPLAY 0.872340 (3050 925);
PAINT AQUA (3050 925);
DISPLAY INVISIBLE (3050 925);
FORCEPROP 2 LAST CDS_LIB logical_power
J 0
(2975 925);
DISPLAY INVISIBLE (2975 925);
FORCEADD UNIVERSAL_GND..1
(2950 -1150);
FORCEPROP 3 LASTPIN (2950 -1100) SIG_NAME T1_GND\g
J 0
(2960 -1090);
DISPLAY 0.659574 (2960 -1090);
PAINT MONO (2960 -1090);
DISPLAY INVISIBLE (2960 -1090);
FORCEPROP 1 LAST HDL_POWER T1_GND
J 1
(2975 -1225);
DISPLAY 0.872340 (2975 -1225);
PAINT GREEN (2975 -1225);
FORCEPROP 1 LAST PATH I83
J 0
(3025 -1150);
DISPLAY 0.872340 (3025 -1150);
PAINT AQUA (3025 -1150);
DISPLAY INVISIBLE (3025 -1150);
FORCEPROP 2 LAST CDS_LIB logical_power
J 0
(2950 -1150);
DISPLAY INVISIBLE (2950 -1150);
FORCEADD UNIVERSAL_GND..1
(2425 3250);
FORCEPROP 3 LASTPIN (2425 3300) SIG_NAME T1_GND\g
J 0
(2435 3310);
DISPLAY 0.659574 (2435 3310);
PAINT MONO (2435 3310);
DISPLAY INVISIBLE (2435 3310);
FORCEPROP 1 LAST HDL_POWER T1_GND
J 1
(2450 3175);
DISPLAY 0.872340 (2450 3175);
PAINT GREEN (2450 3175);
FORCEPROP 1 LAST PATH I84
J 0
(2500 3250);
DISPLAY 0.872340 (2500 3250);
PAINT AQUA (2500 3250);
DISPLAY INVISIBLE (2500 3250);
FORCEPROP 2 LAST CDS_LIB logical_power
J 0
(2425 3250);
DISPLAY INVISIBLE (2425 3250);
FORCEADD UNIVERSAL_GND..1
(275 3250);
FORCEPROP 3 LASTPIN (275 3300) SIG_NAME T1_GND\g
J 0
(285 3310);
DISPLAY 0.659574 (285 3310);
PAINT MONO (285 3310);
DISPLAY INVISIBLE (285 3310);
FORCEPROP 1 LAST HDL_POWER T1_GND
J 1
(300 3175);
DISPLAY 0.872340 (300 3175);
PAINT GREEN (300 3175);
FORCEPROP 1 LAST PATH I85
J 0
(350 3250);
DISPLAY 0.872340 (350 3250);
PAINT AQUA (350 3250);
DISPLAY INVISIBLE (350 3250);
FORCEPROP 2 LAST CDS_LIB logical_power
J 0
(275 3250);
DISPLAY INVISIBLE (275 3250);
FORCEADD UNIVERSAL_GND..1
(2425 4025);
FORCEPROP 3 LASTPIN (2425 4075) SIG_NAME T1_GND\g
J 0
(2435 4085);
DISPLAY 0.659574 (2435 4085);
PAINT MONO (2435 4085);
DISPLAY INVISIBLE (2435 4085);
FORCEPROP 1 LAST HDL_POWER T1_GND
J 1
(2450 3950);
DISPLAY 0.872340 (2450 3950);
PAINT GREEN (2450 3950);
FORCEPROP 1 LAST PATH I86
J 0
(2500 4025);
DISPLAY 0.872340 (2500 4025);
PAINT AQUA (2500 4025);
DISPLAY INVISIBLE (2500 4025);
FORCEPROP 2 LAST CDS_LIB logical_power
J 0
(2425 4025);
DISPLAY INVISIBLE (2425 4025);
FORCEADD UNIVERSAL_GND..1
(275 4025);
FORCEPROP 3 LASTPIN (275 4075) SIG_NAME T1_GND\g
J 0
(285 4085);
DISPLAY 0.659574 (285 4085);
PAINT MONO (285 4085);
DISPLAY INVISIBLE (285 4085);
FORCEPROP 1 LAST HDL_POWER T1_GND
J 1
(300 3950);
DISPLAY 0.872340 (300 3950);
PAINT GREEN (300 3950);
FORCEPROP 1 LAST PATH I87
J 0
(350 4025);
DISPLAY 0.872340 (350 4025);
PAINT AQUA (350 4025);
DISPLAY INVISIBLE (350 4025);
FORCEPROP 2 LAST CDS_LIB logical_power
J 0
(275 4025);
DISPLAY INVISIBLE (275 4025);
FORCEADD UNIVERSAL_GND..1
(275 2475);
FORCEPROP 3 LASTPIN (275 2525) SIG_NAME T1_GND\g
J 0
(285 2535);
DISPLAY 0.659574 (285 2535);
PAINT MONO (285 2535);
DISPLAY INVISIBLE (285 2535);
FORCEPROP 1 LAST HDL_POWER T1_GND
J 1
(300 2400);
DISPLAY 0.872340 (300 2400);
PAINT GREEN (300 2400);
FORCEPROP 1 LAST PATH I88
J 0
(350 2475);
DISPLAY 0.872340 (350 2475);
PAINT AQUA (350 2475);
DISPLAY INVISIBLE (350 2475);
FORCEPROP 2 LAST CDS_LIB logical_power
J 0
(275 2475);
DISPLAY INVISIBLE (275 2475);
FORCEADD UNIVERSAL_GND..1
(2425 2475);
FORCEPROP 3 LASTPIN (2425 2525) SIG_NAME T1_GND\g
J 0
(2435 2535);
DISPLAY 0.659574 (2435 2535);
PAINT MONO (2435 2535);
DISPLAY INVISIBLE (2435 2535);
FORCEPROP 1 LAST HDL_POWER T1_GND
J 1
(2450 2400);
DISPLAY 0.872340 (2450 2400);
PAINT GREEN (2450 2400);
FORCEPROP 1 LAST PATH I89
J 0
(2500 2475);
DISPLAY 0.872340 (2500 2475);
PAINT AQUA (2500 2475);
DISPLAY INVISIBLE (2500 2475);
FORCEPROP 2 LAST CDS_LIB logical_power
J 0
(2425 2475);
DISPLAY INVISIBLE (2425 2475);
FORCEADD TP_TDR_4P_FTS..1
R 4
(4725 2700);
FORCEPROP 1 LAST PART_NUMBER TP15
J 0
(4600 3040);
DISPLAY 0.723404 (4600 3040);
PAINT GREEN (4600 3040);
DISPLAY INVISIBLE (4600 3040);
FORCEPROP 2 LAST PACK_TYPE TH
J 0
(4600 2950);
DISPLAY 1.021277 (4600 2950);
FORCEPROP 2 LAST VALUE TP_TDR_4P_DIP
J 0
(4600 2900);
DISPLAY 1.021277 (4600 2900);
FORCEPROP 1 LAST MATERIAL EMPTY
J 0
(4600 3090);
DISPLAY 0.723404 (4600 3090);
PAINT GREEN (4600 3090);
FORCEPROP 1 LAST $LOCATION X21
J 0
(4600 2995);
DISPLAY 0.723404 (4600 2995);
PAINT GREEN (4600 2995);
FORCEPROP 0 LASTPIN (5000 2625) $PN 2
J 0
(5010 2635);
DISPLAY 0.680851 (5010 2635);
PAINT MONO (5010 2635);
FORCEPROP 0 LASTPIN (5000 2775) $PN 3
J 0
(5010 2785);
DISPLAY 0.680851 (5010 2785);
PAINT MONO (5010 2785);
FORCEPROP 0 LASTPIN (4450 2625) $PN 1
J 2
(4440 2635);
DISPLAY 0.680851 (4440 2635);
PAINT MONO (4440 2635);
FORCEPROP 0 LASTPIN (4450 2775) $PN 4
J 2
(4440 2785);
DISPLAY 0.680851 (4440 2785);
PAINT MONO (4440 2785);
FORCEPROP 2 LAST CDS_LIB pure_quanta
R 2
J 0
(4725 2700);
DISPLAY INVISIBLE (4725 2700);
FORCEPROP 1 LAST NEEDS_NO_SIZE TRUE
R 2
J 0
(4725 2700);
DISPLAY 0.468085 (4725 2700);
PAINT GREEN (4725 2700);
DISPLAY INVISIBLE (4725 2700);
FORCEPROP 1 LAST PATH I9
R 2
J 0
(4625 2520);
DISPLAY 0.723404 (4625 2520);
PAINT GREEN (4625 2520);
DISPLAY INVISIBLE (4625 2520);
FORCEPROP 0 LAST CDS_LOCATION X21
J 0
(4600 3125);
DISPLAY 1.021277 (4600 3125);
DISPLAY INVISIBLE (4600 3125);
FORCEPROP 0 LAST $SEC 1
J 0
(4600 3125);
DISPLAY 0.680851 (4600 3125);
PAINT MONO (4600 3125);
DISPLAY INVISIBLE (4600 3125);
FORCEPROP 0 LAST CDS_SEC 1
J 0
(4600 3125);
DISPLAY 1.021277 (4600 3125);
DISPLAY INVISIBLE (4600 3125);
FORCEADD UNIVERSAL_GND..1
(275 1700);
FORCEPROP 3 LASTPIN (275 1750) SIG_NAME T1_GND\g
J 0
(285 1760);
DISPLAY 0.659574 (285 1760);
PAINT MONO (285 1760);
DISPLAY INVISIBLE (285 1760);
FORCEPROP 1 LAST HDL_POWER T1_GND
J 1
(300 1625);
DISPLAY 0.872340 (300 1625);
PAINT GREEN (300 1625);
FORCEPROP 1 LAST PATH I90
J 0
(350 1700);
DISPLAY 0.872340 (350 1700);
PAINT AQUA (350 1700);
DISPLAY INVISIBLE (350 1700);
FORCEPROP 2 LAST CDS_LIB logical_power
J 0
(275 1700);
DISPLAY INVISIBLE (275 1700);
FORCEADD UNIVERSAL_GND..1
(2425 1700);
FORCEPROP 3 LASTPIN (2425 1750) SIG_NAME T1_GND\g
J 0
(2435 1760);
DISPLAY 0.659574 (2435 1760);
PAINT MONO (2435 1760);
DISPLAY INVISIBLE (2435 1760);
FORCEPROP 1 LAST HDL_POWER T1_GND
J 1
(2450 1625);
DISPLAY 0.872340 (2450 1625);
PAINT GREEN (2450 1625);
FORCEPROP 1 LAST PATH I91
J 0
(2500 1700);
DISPLAY 0.872340 (2500 1700);
PAINT AQUA (2500 1700);
DISPLAY INVISIBLE (2500 1700);
FORCEPROP 2 LAST CDS_LIB logical_power
J 0
(2425 1700);
DISPLAY INVISIBLE (2425 1700);
FORCEADD UNIVERSAL_GND..1
(275 925);
FORCEPROP 3 LASTPIN (275 975) SIG_NAME T1_GND\g
J 0
(285 985);
DISPLAY 0.659574 (285 985);
PAINT MONO (285 985);
DISPLAY INVISIBLE (285 985);
FORCEPROP 1 LAST HDL_POWER T1_GND
J 1
(300 850);
DISPLAY 0.872340 (300 850);
PAINT GREEN (300 850);
FORCEPROP 1 LAST PATH I92
J 0
(350 925);
DISPLAY 0.872340 (350 925);
PAINT AQUA (350 925);
DISPLAY INVISIBLE (350 925);
FORCEPROP 2 LAST CDS_LIB logical_power
J 0
(275 925);
DISPLAY INVISIBLE (275 925);
FORCEADD UNIVERSAL_GND..1
(2425 925);
FORCEPROP 3 LASTPIN (2425 975) SIG_NAME T1_GND\g
J 0
(2435 985);
DISPLAY 0.659574 (2435 985);
PAINT MONO (2435 985);
DISPLAY INVISIBLE (2435 985);
FORCEPROP 1 LAST HDL_POWER T1_GND
J 1
(2450 850);
DISPLAY 0.872340 (2450 850);
PAINT GREEN (2450 850);
FORCEPROP 1 LAST PATH I93
J 0
(2500 925);
DISPLAY 0.872340 (2500 925);
PAINT AQUA (2500 925);
DISPLAY INVISIBLE (2500 925);
FORCEPROP 2 LAST CDS_LIB logical_power
J 0
(2425 925);
DISPLAY INVISIBLE (2425 925);
FORCEADD UNIVERSAL_GND..1
(275 -1150);
FORCEPROP 3 LASTPIN (275 -1100) SIG_NAME T1_GND\g
J 0
(285 -1090);
DISPLAY 0.659574 (285 -1090);
PAINT MONO (285 -1090);
DISPLAY INVISIBLE (285 -1090);
FORCEPROP 1 LAST HDL_POWER T1_GND
J 1
(300 -1225);
DISPLAY 0.872340 (300 -1225);
PAINT GREEN (300 -1225);
FORCEPROP 1 LAST PATH I94
J 0
(350 -1150);
DISPLAY 0.872340 (350 -1150);
PAINT AQUA (350 -1150);
DISPLAY INVISIBLE (350 -1150);
FORCEPROP 2 LAST CDS_LIB logical_power
J 0
(275 -1150);
DISPLAY INVISIBLE (275 -1150);
FORCEADD UNIVERSAL_GND..1
(2425 -1150);
FORCEPROP 3 LASTPIN (2425 -1100) SIG_NAME T1_GND\g
J 0
(2435 -1090);
DISPLAY 0.659574 (2435 -1090);
PAINT MONO (2435 -1090);
DISPLAY INVISIBLE (2435 -1090);
FORCEPROP 1 LAST HDL_POWER T1_GND
J 1
(2450 -1225);
DISPLAY 0.872340 (2450 -1225);
PAINT GREEN (2450 -1225);
FORCEPROP 1 LAST PATH I95
J 0
(2500 -1150);
DISPLAY 0.872340 (2500 -1150);
PAINT AQUA (2500 -1150);
DISPLAY INVISIBLE (2500 -1150);
FORCEPROP 2 LAST CDS_LIB logical_power
J 0
(2425 -1150);
DISPLAY INVISIBLE (2425 -1150);
FORCEADD TDR_3P..2
(-2875 1125);
FORCEPROP 1 LAST PART_NUMBER N_A
J 1
(-2815 975);
DISPLAY 0.872340 (-2815 975);
PAINT PINK (-2815 975);
DISPLAY INVISIBLE (-2815 975);
FORCEPROP 1 LAST PACK_TYPE TH2
J 2
(-2850 1275);
DISPLAY 0.872340 (-2850 1275);
FORCEPROP 1 LAST $LOCATION DB14
J 2
(-2850 1325);
DISPLAY 0.872340 (-2850 1325);
PAINT PINK (-2850 1325);
FORCEPROP 0 LASTPIN (-3075 1125) $PN 1
J 2
(-3085 1135);
DISPLAY 0.680851 (-3085 1135);
PAINT MONO (-3085 1135);
FORCEPROP 0 LASTPIN (-2775 1175) $PN 2
J 0
(-2765 1185);
DISPLAY 0.680851 (-2765 1185);
PAINT MONO (-2765 1185);
FORCEPROP 0 LASTPIN (-2775 1075) $PN 3
J 0
(-2765 1085);
DISPLAY 0.680851 (-2765 1085);
PAINT MONO (-2765 1085);
FORCEPROP 1 LAST PATH I96
J 2
(-2575 1275);
DISPLAY 0.872340 (-2575 1275);
PAINT PINK (-2575 1275);
DISPLAY INVISIBLE (-2575 1275);
FORCEPROP 1 LAST CDS_LMAN_SYM_OUTLINE -150,100,50,-100
J 0
(-2875 1125);
DISPLAY 0.468085 (-2875 1125);
PAINT GREEN (-2875 1125);
DISPLAY INVISIBLE (-2875 1125);
FORCEPROP 2 LAST CDS_LIB pure_quanta
J 0
(-2875 1125);
DISPLAY INVISIBLE (-2875 1125);
FORCEPROP 1 LAST MATERIAL EMPTY
J 2
(-2875 1275);
DISPLAY 0.872340 (-2875 1275);
PAINT PINK (-2875 1275);
DISPLAY INVISIBLE (-2875 1275);
FORCEPROP 0 LAST CDS_LOCATION DB14
J 0
(-2850 1375);
DISPLAY 1.021277 (-2850 1375);
DISPLAY INVISIBLE (-2850 1375);
FORCEPROP 0 LAST $SEC 1
J 0
(-2850 1375);
DISPLAY 0.680851 (-2850 1375);
PAINT MONO (-2850 1375);
DISPLAY INVISIBLE (-2850 1375);
FORCEPROP 0 LAST CDS_SEC 1
J 0
(-2850 1375);
DISPLAY 1.021277 (-2850 1375);
DISPLAY INVISIBLE (-2850 1375);
FORCEADD TDR_3P..2
(-1175 1650);
FORCEPROP 1 LAST PART_NUMBER N_A
J 1
(-1115 1500);
DISPLAY 0.872340 (-1115 1500);
PAINT PINK (-1115 1500);
DISPLAY INVISIBLE (-1115 1500);
FORCEPROP 1 LAST PACK_TYPE TH2
J 2
(-1150 1800);
DISPLAY 0.872340 (-1150 1800);
FORCEPROP 1 LAST $LOCATION DB15
J 2
(-1150 1850);
DISPLAY 0.872340 (-1150 1850);
PAINT PINK (-1150 1850);
FORCEPROP 0 LASTPIN (-1375 1650) $PN 1
J 2
(-1385 1660);
DISPLAY 0.680851 (-1385 1660);
PAINT MONO (-1385 1660);
FORCEPROP 0 LASTPIN (-1075 1700) $PN 2
J 0
(-1065 1710);
DISPLAY 0.680851 (-1065 1710);
PAINT MONO (-1065 1710);
FORCEPROP 0 LASTPIN (-1075 1600) $PN 3
J 0
(-1065 1610);
DISPLAY 0.680851 (-1065 1610);
PAINT MONO (-1065 1610);
FORCEPROP 1 LAST PATH I97
J 2
(-875 1800);
DISPLAY 0.872340 (-875 1800);
PAINT PINK (-875 1800);
DISPLAY INVISIBLE (-875 1800);
FORCEPROP 1 LAST CDS_LMAN_SYM_OUTLINE -150,100,50,-100
J 0
(-1175 1650);
DISPLAY 0.468085 (-1175 1650);
PAINT GREEN (-1175 1650);
DISPLAY INVISIBLE (-1175 1650);
FORCEPROP 2 LAST CDS_LIB pure_quanta
J 0
(-1175 1650);
DISPLAY INVISIBLE (-1175 1650);
FORCEPROP 1 LAST MATERIAL EMPTY
J 2
(-1175 1800);
DISPLAY 0.872340 (-1175 1800);
PAINT PINK (-1175 1800);
DISPLAY INVISIBLE (-1175 1800);
FORCEPROP 0 LAST CDS_LOCATION DB15
J 0
(-1150 1900);
DISPLAY 1.021277 (-1150 1900);
DISPLAY INVISIBLE (-1150 1900);
FORCEPROP 0 LAST $SEC 1
J 0
(-1150 1900);
DISPLAY 0.680851 (-1150 1900);
PAINT MONO (-1150 1900);
DISPLAY INVISIBLE (-1150 1900);
FORCEPROP 0 LAST CDS_SEC 1
J 0
(-1150 1900);
DISPLAY 1.021277 (-1150 1900);
DISPLAY INVISIBLE (-1150 1900);
FORCEADD UNIVERSAL_GND..1
(-1525 1425);
FORCEPROP 3 LASTPIN (-1525 1475) SIG_NAME T1_GND\g
J 0
(-1515 1485);
DISPLAY 0.659574 (-1515 1485);
PAINT MONO (-1515 1485);
DISPLAY INVISIBLE (-1515 1485);
FORCEPROP 1 LAST HDL_POWER T1_GND
J 1
(-1500 1350);
DISPLAY 0.872340 (-1500 1350);
PAINT GREEN (-1500 1350);
FORCEPROP 1 LAST PATH I98
J 0
(-1450 1425);
DISPLAY 0.872340 (-1450 1425);
PAINT AQUA (-1450 1425);
DISPLAY INVISIBLE (-1450 1425);
FORCEPROP 2 LAST CDS_LIB logical_power
J 0
(-1525 1425);
DISPLAY INVISIBLE (-1525 1425);
FORCEADD TDR_3P..2
(-1175 1125);
FORCEPROP 1 LAST PART_NUMBER N_A
J 1
(-1115 975);
DISPLAY 0.872340 (-1115 975);
PAINT PINK (-1115 975);
DISPLAY INVISIBLE (-1115 975);
FORCEPROP 1 LAST PACK_TYPE TH2
J 2
(-1150 1275);
DISPLAY 0.872340 (-1150 1275);
FORCEPROP 1 LAST $LOCATION DB16
J 2
(-1150 1325);
DISPLAY 0.872340 (-1150 1325);
PAINT PINK (-1150 1325);
FORCEPROP 0 LASTPIN (-1375 1125) $PN 1
J 2
(-1385 1135);
DISPLAY 0.680851 (-1385 1135);
PAINT MONO (-1385 1135);
FORCEPROP 0 LASTPIN (-1075 1175) $PN 2
J 0
(-1065 1185);
DISPLAY 0.680851 (-1065 1185);
PAINT MONO (-1065 1185);
FORCEPROP 0 LASTPIN (-1075 1075) $PN 3
J 0
(-1065 1085);
DISPLAY 0.680851 (-1065 1085);
PAINT MONO (-1065 1085);
FORCEPROP 1 LAST PATH I99
J 2
(-875 1275);
DISPLAY 0.872340 (-875 1275);
PAINT PINK (-875 1275);
DISPLAY INVISIBLE (-875 1275);
FORCEPROP 1 LAST MATERIAL EMPTY
J 2
(-1175 1275);
DISPLAY 0.872340 (-1175 1275);
PAINT PINK (-1175 1275);
DISPLAY INVISIBLE (-1175 1275);
FORCEPROP 2 LAST CDS_LIB pure_quanta
J 0
(-1175 1125);
DISPLAY INVISIBLE (-1175 1125);
FORCEPROP 1 LAST CDS_LMAN_SYM_OUTLINE -150,100,50,-100
J 0
(-1175 1125);
DISPLAY 0.468085 (-1175 1125);
PAINT GREEN (-1175 1125);
DISPLAY INVISIBLE (-1175 1125);
FORCEPROP 0 LAST CDS_LOCATION DB16
J 0
(-1150 1375);
DISPLAY 1.021277 (-1150 1375);
DISPLAY INVISIBLE (-1150 1375);
FORCEPROP 0 LAST $SEC 1
J 0
(-1150 1375);
DISPLAY 0.680851 (-1150 1375);
PAINT MONO (-1150 1375);
DISPLAY INVISIBLE (-1150 1375);
FORCEPROP 0 LAST CDS_SEC 1
J 0
(-1150 1375);
DISPLAY 1.021277 (-1150 1375);
DISPLAY INVISIBLE (-1150 1375);
FORCEADD QUANTA_TITLE_BLOCK_C..1
(5625 -1575);
FORCEPROP 0 LAST CDS_CON_LAST_MODIFIED Fri Aug 25 14:05:30 2023
J 0
(3740 -1560);
PAINT MONO (3740 -1560);
DISPLAY INVISIBLE (3740 -1560);
FORCEPROP 2 LAST CUSTOM_TXT_CDS <XR_PAGE_TITLE>
J 0
(-2265 3675);
DISPLAY 0.638298 (-2265 3675);
PAINT PINK (-2265 3675);
DISPLAY INVISIBLE (-2265 3675);
FORCEPROP 2 LAST CUSTOM_TXT_CDS <CON_PAGE_NUM> OF <CON_TOTAL_PAGES>
J 0
(5179 -1557);
DISPLAY 0.978723 (5179 -1557);
FORCEPROP 2 LAST CUSTOM_TXT_CDS <Q_REV>
J 0
(5441 -1472);
DISPLAY 1.212766 (5441 -1472);
FORCEPROP 2 LAST CUSTOM_TXT_CDS <Q_PROJ>
J 0
(3243 -1473);
DISPLAY 1.212766 (3243 -1473);
FORCEPROP 2 LAST CUSTOM_TXT_CDS <NAME_2>
J 0
(2450 -1525);
FORCEPROP 2 LAST CUSTOM_TXT_CDS <NAME_1>
J 0
(2450 -1400);
FORCEPROP 2 LAST CUSTOM_TXT_CDS <CON_LAST_MODIFIED>
J 0
(3740 -1560);
DISPLAY 0.978723 (3740 -1560);
FORCEPROP 2 LAST CUSTOM_TXT_CDS <Q_NUMBER>
J 0
(4222 -1472);
DISPLAY 1.212766 (4222 -1472);
FORCEPROP 1 LAST Q_TITLE TDR
J 0
(-3641 -1524);
DISPLAY 2.446809 (-3641 -1524);
PAINT GREEN (-3641 -1524);
FORCEPROP 1 LAST Q_DEPT 
J 1
(1862 -1526);
DISPLAY 1.957447 (1862 -1526);
PAINT GREEN (1862 -1526);
FORCEPROP 2 LAST CDS_XR_PAGE_TITLE CR-309 : @S9S_MB_2U_LIB.S9S_MB_2U(SCH_1):PAGE309
J 0
(-2265 3675);
DISPLAY 0.638298 (-2265 3675);
PAINT PINK (-2265 3675);
DISPLAY INVISIBLE (-2265 3675);
FORCEPROP 2 LAST PAGE_BORDER TRUE
J 0
(-2265 3675);
DISPLAY 0.638298 (-2265 3675);
PAINT PINK (-2265 3675);
DISPLAY INVISIBLE (-2265 3675);
FORCEPROP 1 LAST COMMENT_BODY TRUE
J 0
(5637 -1588);
DISPLAY 0.978723 (5637 -1588);
PAINT GREEN (5637 -1588);
DISPLAY INVISIBLE (5637 -1588);
FORCEPROP 1 LAST CDS_LMAN_SYM_OUTLINE -9475,6775,100,-125
J 0
(5625 -1575);
DISPLAY 0.468085 (5625 -1575);
PAINT GREEN (5625 -1575);
DISPLAY INVISIBLE (5625 -1575);
FORCEPROP 2 LAST CDS_LIB pure_quanta
J 0
(5625 -1575);
PAINT MONO (5625 -1575);
DISPLAY INVISIBLE (5625 -1575);
WIRE 16 -1 (275 -475)(275 -375);
WIRE 16 -1 (-3200 4100)(-3200 4275);
WIRE 16 -1 (2425 2525)(2425 2625);
WIRE 16 -1 (-3225 1475)(-3225 1650);
WIRE 16 -1 (-3200 2000)(-3200 2175);
WIRE 16 -1 (-3200 2525)(-3200 2700);
WIRE 16 -1 (-3200 3575)(-3200 3750);
WIRE 16 -1 (275 3300)(275 3400);
WIRE 16 -1 (2425 4075)(2425 4175);
WIRE 16 -1 (2975 3300)(2975 3400);
WIRE 16 -1 (-1550 400)(-1550 575);
WIRE 16 -1 (-3250 400)(-3250 575);
WIRE 16 -1 (-1525 950)(-1525 1125);
WIRE 16 -1 (-1525 1475)(-1525 1650);
WIRE 16 -1 (-1500 2000)(-1500 2175);
WIRE 16 -1 (-1500 2525)(-1500 2700);
WIRE 16 -1 (-1500 3050)(-1500 3225);
WIRE 16 -1 (-1500 3575)(-1500 3750);
WIRE 16 -1 (-3225 950)(-3225 1125);
WIRE 16 -1 (-3200 3050)(-3200 3225);
WIRE 16 -1 (-1500 4100)(-1500 4275);
WIRE 16 -1 (275 1750)(275 1850);
WIRE 16 -1 (275 975)(275 1075);
WIRE 16 -1 (2425 1750)(2425 1850);
WIRE 16 -1 (2975 4075)(2975 4175);
WIRE 16 -1 (5125 2525)(5125 2625);
WIRE 16 -1 (2425 3300)(2425 3400);
WIRE 16 -1 (2975 2525)(2975 2625);
WIRE 16 -1 (2975 1750)(2975 1850);
WIRE 16 -1 (5100 300)(5100 400);
WIRE 16 -1 (2950 -1100)(2950 -1025);
WIRE 16 -1 (5100 -1100)(5100 -1025);
WIRE 16 -1 (2975 975)(2975 1075);
WIRE 16 -1 (5125 975)(5125 1075);
WIRE 16 -1 (5125 1750)(5125 1850);
WIRE 16 -1 (5100 -475)(5100 -375);
WIRE 16 -1 (2950 300)(2950 400);
WIRE 16 -1 (2950 -475)(2950 -375);
WIRE 16 -1 (2425 -1100)(2425 -1025);
WIRE 16 -1 (275 -1100)(275 -1025);
WIRE 16 -1 (2425 -475)(2425 -375);
WIRE 16 -1 (275 300)(275 400);
WIRE 16 -1 (2425 975)(2425 1075);
WIRE 16 -1 (2425 300)(2425 400);
WIRE 16 -1 (5125 4075)(5125 4175);
WIRE 16 -1 (5125 3300)(5125 3400);
WIRE 16 -1 (275 4075)(275 4175);
WIRE 16 -1 (275 2525)(275 2625);
WIRE 16 -1 (-2075 1075)(-2775 1075);
WIRE 16 -1 (-2075 1175)(-2775 1175);
FORCEPROP 0 LAST CDS_PHYS_NET_NAME TDR_SE_40_OHM_IN4
J 0
(-2735 1215);
PAINT MONO (-2735 1215);
DISPLAY INVISIBLE (-2735 1215);
FORCEPROP 2 LAST SIG_NAME TDR_SE_40_OHM_IN6
J 0
(-2660 1185);
DISPLAY 0.638298 (-2660 1185);
PAINT WHITE (-2660 1185);
WIRE 16 -1 (-2075 1175)(-2075 1075);
WIRE 16 -1 (275 -225)(425 -225);
WIRE 16 -1 (275 -375)(425 -375);
WIRE 16 -1 (275 -375)(275 -225);
WIRE 16 -1 (-400 525)(-1100 525);
WIRE 16 -1 (-400 625)(-1100 625);
FORCEPROP 0 LAST CDS_PHYS_NET_NAME TDR_SE_50_OHM_BOT
J 0
(-1060 665);
PAINT MONO (-1060 665);
DISPLAY INVISIBLE (-1060 665);
FORCEPROP 2 LAST SIG_NAME TDR_SE_50_OHM_BOT
J 0
(-985 635);
DISPLAY 0.638298 (-985 635);
PAINT WHITE (-985 635);
WIRE 16 -1 (-400 625)(-400 525);
WIRE 16 -1 (-375 1075)(-1075 1075);
WIRE 16 -1 (-375 1175)(-1075 1175);
FORCEPROP 0 LAST CDS_PHYS_NET_NAME TDR_SE_50_OHM_IN4
J 0
(-1035 1215);
PAINT MONO (-1035 1215);
DISPLAY INVISIBLE (-1035 1215);
FORCEPROP 2 LAST SIG_NAME TDR_SE_50_OHM_IN6
J 0
(-960 1185);
DISPLAY 0.638298 (-960 1185);
PAINT WHITE (-960 1185);
WIRE 16 -1 (-375 1175)(-375 1075);
WIRE 16 -1 (-2050 2650)(-2750 2650);
WIRE 16 -1 (-2050 2750)(-2750 2750);
FORCEPROP 0 LAST CDS_PHYS_NET_NAME TDR_SE_40_OHM_IN3
J 0
(-2710 2790);
PAINT MONO (-2710 2790);
DISPLAY INVISIBLE (-2710 2790);
FORCEPROP 2 LAST SIG_NAME TDR_SE_40_OHM_IN3
J 0
(-2635 2760);
DISPLAY 0.638298 (-2635 2760);
PAINT WHITE (-2635 2760);
WIRE 16 -1 (-2050 2750)(-2050 2650);
WIRE 16 -1 (1750 2000)(975 2000);
FORCEPROP 0 LAST CDS_PHYS_NET_NAME TDR_DIFF_85_IN3_DP
J 0
(1015 2040);
PAINT MONO (1015 2040);
DISPLAY INVISIBLE (1015 2040);
FORCEPROP 2 LAST SIG_NAME TDR_DIFF_85_IN3_DP
J 0
(1090 2010);
DISPLAY 0.638298 (1090 2010);
PAINT WHITE (1090 2010);
WIRE 16 -1 (2425 3550)(2300 3550);
WIRE 16 -1 (2300 3400)(2425 3400);
WIRE 16 -1 (2425 3400)(2425 3550);
WIRE 16 -1 (-350 3700)(-1050 3700);
WIRE 16 -1 (-350 3800)(-1050 3800);
FORCEPROP 0 LAST CDS_PHYS_NET_NAME TDR_SE_50_OHM_IN1
J 0
(-1010 3840);
PAINT MONO (-1010 3840);
DISPLAY INVISIBLE (-1010 3840);
FORCEPROP 2 LAST SIG_NAME TDR_SE_50_OHM_IN1
J 0
(-935 3810);
DISPLAY 0.638298 (-935 3810);
PAINT WHITE (-935 3810);
WIRE 16 -1 (-350 3800)(-350 3700);
WIRE 16 -1 (-350 2650)(-1050 2650);
WIRE 16 -1 (-350 2750)(-1050 2750);
FORCEPROP 0 LAST CDS_PHYS_NET_NAME TDR_SE_50_OHM_IN3
J 0
(-1010 2790);
PAINT MONO (-1010 2790);
DISPLAY INVISIBLE (-1010 2790);
FORCEPROP 2 LAST SIG_NAME TDR_SE_50_OHM_IN3
J 0
(-935 2760);
DISPLAY 0.638298 (-935 2760);
PAINT WHITE (-935 2760);
WIRE 16 -1 (-350 2750)(-350 2650);
WIRE 16 -1 (-350 2125)(-1050 2125);
WIRE 16 -1 (-350 2225)(-1050 2225);
FORCEPROP 0 LAST CDS_PHYS_NET_NAME TDR_SE_50_OHM_IN4
J 0
(-1010 2265);
PAINT MONO (-1010 2265);
DISPLAY INVISIBLE (-1010 2265);
FORCEPROP 2 LAST SIG_NAME TDR_SE_50_OHM_IN4
J 0
(-935 2235);
DISPLAY 0.638298 (-935 2235);
PAINT WHITE (-935 2235);
WIRE 16 -1 (-350 2225)(-350 2125);
WIRE 16 -1 (-3200 2175)(-3050 2175);
WIRE 16 -1 (2975 3550)(3125 3550);
WIRE 16 -1 (2975 3400)(2975 3550);
WIRE 16 -1 (2975 3400)(3125 3400);
WIRE 16 -1 (4450 2000)(3675 2000);
FORCEPROP 0 LAST CDS_PHYS_NET_NAME TDR_DIFF_100_IN3_DP
J 0
(3715 2040);
PAINT MONO (3715 2040);
DISPLAY INVISIBLE (3715 2040);
FORCEPROP 2 LAST SIG_NAME TDR_DIFF_100_IN3_DP
J 0
(3790 2010);
DISPLAY 0.638298 (3790 2010);
PAINT WHITE (3790 2010);
WIRE 16 -1 (4450 1850)(3675 1850);
FORCEPROP 0 LAST CDS_PHYS_NET_NAME TDR_DIFF_100_IN3_DN
J 0
(3715 1890);
PAINT MONO (3715 1890);
DISPLAY INVISIBLE (3715 1890);
FORCEPROP 2 LAST SIG_NAME TDR_DIFF_100_IN3_DN
J 0
(3790 1860);
DISPLAY 0.638298 (3790 1860);
PAINT WHITE (3790 1860);
WIRE 16 -1 (4450 1075)(3675 1075);
FORCEPROP 0 LAST CDS_PHYS_NET_NAME TDR_DIFF_100_IN4_DN
J 0
(3715 1115);
PAINT MONO (3715 1115);
DISPLAY INVISIBLE (3715 1115);
FORCEPROP 2 LAST SIG_NAME TDR_DIFF_100_IN4_DN
J 0
(3790 1085);
DISPLAY 0.638298 (3790 1085);
PAINT WHITE (3790 1085);
WIRE 16 -1 (4425 550)(3650 550);
FORCEPROP 0 LAST CDS_PHYS_NET_NAME TDR_DIFF_100_IN3_DP
J 0
(3690 590);
PAINT MONO (3690 590);
DISPLAY INVISIBLE (3690 590);
FORCEPROP 2 LAST SIG_NAME TDR_DIFF_100_IN5_DP
J 0
(3765 560);
DISPLAY 0.638298 (3765 560);
PAINT WHITE (3765 560);
WIRE 16 -1 (-2050 3700)(-2750 3700);
WIRE 16 -1 (-2050 3800)(-2750 3800);
FORCEPROP 0 LAST CDS_PHYS_NET_NAME TDR_SE_40_OHM_IN1
J 0
(-2710 3840);
PAINT MONO (-2710 3840);
DISPLAY INVISIBLE (-2710 3840);
FORCEPROP 2 LAST SIG_NAME TDR_SE_40_OHM_IN1
J 0
(-2635 3810);
DISPLAY 0.638298 (-2635 3810);
PAINT WHITE (-2635 3810);
WIRE 16 -1 (-2050 3800)(-2050 3700);
WIRE 16 -1 (-350 3175)(-1050 3175);
WIRE 16 -1 (-350 3275)(-1050 3275);
FORCEPROP 0 LAST CDS_PHYS_NET_NAME TDR_SE_50_OHM_IN2
J 0
(-1010 3315);
PAINT MONO (-1010 3315);
DISPLAY INVISIBLE (-1010 3315);
FORCEPROP 2 LAST SIG_NAME TDR_SE_50_OHM_IN2
J 0
(-935 3285);
DISPLAY 0.638298 (-935 3285);
PAINT WHITE (-935 3285);
WIRE 16 -1 (-350 3275)(-350 3175);
WIRE 16 -1 (275 550)(425 550);
WIRE 16 -1 (275 400)(425 400);
WIRE 16 -1 (275 400)(275 550);
WIRE 16 -1 (1750 400)(975 400);
FORCEPROP 0 LAST CDS_PHYS_NET_NAME TDR_DIFF_85_IN3_DN
J 0
(1015 440);
PAINT MONO (1015 440);
DISPLAY INVISIBLE (1015 440);
FORCEPROP 2 LAST SIG_NAME TDR_DIFF_85_IN5_DN
J 0
(1090 410);
DISPLAY 0.638298 (1090 410);
PAINT WHITE (1090 410);
WIRE 16 -1 (275 1225)(425 1225);
WIRE 16 -1 (275 1075)(275 1225);
WIRE 16 -1 (275 1075)(425 1075);
WIRE 16 -1 (1750 550)(975 550);
FORCEPROP 0 LAST CDS_PHYS_NET_NAME TDR_DIFF_85_IN3_DP
J 0
(1015 590);
PAINT MONO (1015 590);
DISPLAY INVISIBLE (1015 590);
FORCEPROP 2 LAST SIG_NAME TDR_DIFF_85_IN5_DP
J 0
(1090 560);
DISPLAY 0.638298 (1090 560);
PAINT WHITE (1090 560);
WIRE 16 -1 (1750 1075)(975 1075);
FORCEPROP 0 LAST CDS_PHYS_NET_NAME TDR_DIFF_85_IN4_DN
J 0
(1015 1115);
PAINT MONO (1015 1115);
DISPLAY INVISIBLE (1015 1115);
FORCEPROP 2 LAST SIG_NAME TDR_DIFF_85_IN4_DN
J 0
(1090 1085);
DISPLAY 0.638298 (1090 1085);
PAINT WHITE (1090 1085);
WIRE 16 -1 (1750 1225)(975 1225);
FORCEPROP 0 LAST CDS_PHYS_NET_NAME TDR_DIFF_85_IN4_DP
J 0
(1015 1265);
PAINT MONO (1015 1265);
DISPLAY INVISIBLE (1015 1265);
FORCEPROP 2 LAST SIG_NAME TDR_DIFF_85_IN4_DP
J 0
(1090 1235);
DISPLAY 0.638298 (1090 1235);
PAINT WHITE (1090 1235);
WIRE 16 -1 (-1500 2700)(-1350 2700);
WIRE 16 -1 (-1500 3750)(-1350 3750);
WIRE 16 -1 (-1500 3225)(-1350 3225);
WIRE 16 -1 (275 2775)(425 2775);
WIRE 16 -1 (275 2625)(275 2775);
WIRE 16 -1 (275 2625)(425 2625);
WIRE 16 -1 (275 1850)(425 1850);
WIRE 16 -1 (275 1850)(275 2000);
WIRE 16 -1 (275 2000)(425 2000);
WIRE 16 -1 (1750 1850)(975 1850);
FORCEPROP 0 LAST CDS_PHYS_NET_NAME TDR_DIFF_85_IN3_DN
J 0
(1015 1890);
PAINT MONO (1015 1890);
DISPLAY INVISIBLE (1015 1890);
FORCEPROP 2 LAST SIG_NAME TDR_DIFF_85_IN3_DN
J 0
(1090 1860);
DISPLAY 0.638298 (1090 1860);
PAINT WHITE (1090 1860);
WIRE 16 -1 (1750 2775)(975 2775);
FORCEPROP 0 LAST CDS_PHYS_NET_NAME TDR_DIFF_85_IN2_DP
J 0
(1015 2815);
PAINT MONO (1015 2815);
DISPLAY INVISIBLE (1015 2815);
FORCEPROP 2 LAST SIG_NAME TDR_DIFF_85_IN2_DP
J 0
(1090 2785);
DISPLAY 0.638298 (1090 2785);
PAINT WHITE (1090 2785);
WIRE 16 -1 (1750 3550)(975 3550);
FORCEPROP 0 LAST CDS_PHYS_NET_NAME TDR_DIFF_85_IN1_DP
J 0
(1015 3590);
PAINT MONO (1015 3590);
DISPLAY INVISIBLE (1015 3590);
FORCEPROP 2 LAST SIG_NAME TDR_DIFF_85_IN1_DP
J 0
(1090 3560);
DISPLAY 0.638298 (1090 3560);
PAINT WHITE (1090 3560);
WIRE 16 -1 (1750 4175)(975 4175);
FORCEPROP 0 LAST CDS_PHYS_NET_NAME TDR_DIFF_85_TOP_DN
J 0
(1015 4215);
PAINT MONO (1015 4215);
DISPLAY INVISIBLE (1015 4215);
FORCEPROP 2 LAST SIG_NAME TDR_DIFF_85_TOP_DN
J 0
(1090 4185);
DISPLAY 0.638298 (1090 4185);
PAINT WHITE (1090 4185);
WIRE 16 -1 (1750 4325)(975 4325);
FORCEPROP 0 LAST CDS_PHYS_NET_NAME TDR_DIFF_85_TOP_DP
J 0
(1015 4365);
PAINT MONO (1015 4365);
DISPLAY INVISIBLE (1015 4365);
FORCEPROP 2 LAST SIG_NAME TDR_DIFF_85_TOP_DP
J 0
(1090 4335);
DISPLAY 0.638298 (1090 4335);
PAINT WHITE (1090 4335);
WIRE 16 -1 (2975 2775)(3125 2775);
WIRE 16 -1 (2975 2625)(2975 2775);
WIRE 16 -1 (2975 2625)(3125 2625);
WIRE 16 -1 (4450 2625)(3675 2625);
FORCEPROP 0 LAST CDS_PHYS_NET_NAME TDR_DIFF_100_IN2_DN
J 0
(3715 2665);
PAINT MONO (3715 2665);
DISPLAY INVISIBLE (3715 2665);
FORCEPROP 2 LAST SIG_NAME TDR_DIFF_100_IN2_DN
J 0
(3790 2635);
DISPLAY 0.638298 (3790 2635);
PAINT WHITE (3790 2635);
WIRE 16 -1 (275 3400)(425 3400);
WIRE 16 -1 (275 3400)(275 3550);
WIRE 16 -1 (275 3550)(425 3550);
WIRE 16 -1 (2975 1075)(3125 1075);
WIRE 16 -1 (2975 1075)(2975 1225);
WIRE 16 -1 (2975 1225)(3125 1225);
WIRE 16 -1 (-375 1600)(-1075 1600);
WIRE 16 -1 (-375 1700)(-1075 1700);
FORCEPROP 0 LAST CDS_PHYS_NET_NAME TDR_SE_50_OHM_IN3
J 0
(-1035 1740);
PAINT MONO (-1035 1740);
DISPLAY INVISIBLE (-1035 1740);
FORCEPROP 2 LAST SIG_NAME TDR_SE_50_OHM_IN5
J 0
(-960 1710);
DISPLAY 0.638298 (-960 1710);
PAINT WHITE (-960 1710);
WIRE 16 -1 (-375 1700)(-375 1600);
WIRE 16 -1 (2950 -375)(3100 -375);
WIRE 16 -1 (2950 -375)(2950 -225);
WIRE 16 -1 (2950 -225)(3100 -225);
WIRE 16 -1 (4425 -225)(3650 -225);
FORCEPROP 0 LAST CDS_PHYS_NET_NAME TDR_DIFF_100_IN4_DP
J 0
(3690 -185);
PAINT MONO (3690 -185);
DISPLAY INVISIBLE (3690 -185);
FORCEPROP 2 LAST SIG_NAME TDR_DIFF_100_IN6_DP
J 0
(3765 -215);
DISPLAY 0.638298 (3765 -215);
PAINT WHITE (3765 -215);
WIRE 16 -1 (4425 -375)(3650 -375);
FORCEPROP 0 LAST CDS_PHYS_NET_NAME TDR_DIFF_100_IN4_DN
J 0
(3690 -335);
PAINT MONO (3690 -335);
DISPLAY INVISIBLE (3690 -335);
FORCEPROP 2 LAST SIG_NAME TDR_DIFF_100_IN6_DN
J 0
(3765 -365);
DISPLAY 0.638298 (3765 -365);
PAINT WHITE (3765 -365);
WIRE 16 -1 (4425 -875)(3650 -875);
FORCEPROP 0 LAST CDS_PHYS_NET_NAME TDR_DIFF_100_BOT_DP
J 0
(3690 -835);
PAINT MONO (3690 -835);
DISPLAY INVISIBLE (3690 -835);
FORCEPROP 2 LAST SIG_NAME TDR_DIFF_100_BOT_DP
J 0
(3765 -865);
DISPLAY 0.638298 (3765 -865);
PAINT WHITE (3765 -865);
WIRE 16 -1 (4425 -1025)(3650 -1025);
FORCEPROP 0 LAST CDS_PHYS_NET_NAME TDR_DIFF_100_BOT_DN
J 0
(3690 -985);
PAINT MONO (3690 -985);
DISPLAY INVISIBLE (3690 -985);
FORCEPROP 2 LAST SIG_NAME TDR_DIFF_100_BOT_DN
J 0
(3765 -1015);
DISPLAY 0.638298 (3765 -1015);
PAINT WHITE (3765 -1015);
WIRE 16 -1 (2950 -1025)(3100 -1025);
WIRE 16 -1 (2950 -875)(2950 -1025);
WIRE 16 -1 (2950 -875)(3100 -875);
WIRE 16 -1 (4975 -1025)(5100 -1025);
WIRE 16 -1 (5100 -875)(5100 -1025);
WIRE 16 -1 (5100 -875)(4975 -875);
WIRE 16 -1 (5125 2000)(5000 2000);
WIRE 16 -1 (5000 1850)(5125 1850);
WIRE 16 -1 (5125 1850)(5125 2000);
WIRE 16 -1 (5125 1225)(5000 1225);
WIRE 16 -1 (5000 1075)(5125 1075);
WIRE 16 -1 (5125 1075)(5125 1225);
WIRE 16 -1 (4450 1225)(3675 1225);
FORCEPROP 0 LAST CDS_PHYS_NET_NAME TDR_DIFF_100_IN4_DP
J 0
(3715 1265);
PAINT MONO (3715 1265);
DISPLAY INVISIBLE (3715 1265);
FORCEPROP 2 LAST SIG_NAME TDR_DIFF_100_IN4_DP
J 0
(3790 1235);
DISPLAY 0.638298 (3790 1235);
PAINT WHITE (3790 1235);
WIRE 16 -1 (2975 2000)(3125 2000);
WIRE 16 -1 (2975 1850)(2975 2000);
WIRE 16 -1 (2975 1850)(3125 1850);
WIRE 16 -1 (2950 400)(3100 400);
WIRE 16 -1 (2950 400)(2950 550);
WIRE 16 -1 (2950 550)(3100 550);
WIRE 16 -1 (4425 400)(3650 400);
FORCEPROP 0 LAST CDS_PHYS_NET_NAME TDR_DIFF_100_IN3_DN
J 0
(3690 440);
PAINT MONO (3690 440);
DISPLAY INVISIBLE (3690 440);
FORCEPROP 2 LAST SIG_NAME TDR_DIFF_100_IN5_DN
J 0
(3765 410);
DISPLAY 0.638298 (3765 410);
PAINT WHITE (3765 410);
WIRE 16 -1 (4975 -375)(5100 -375);
WIRE 16 -1 (5100 -375)(5100 -225);
WIRE 16 -1 (5100 -225)(4975 -225);
WIRE 16 -1 (5100 550)(4975 550);
WIRE 16 -1 (5100 400)(5100 550);
WIRE 16 -1 (4975 400)(5100 400);
WIRE 16 -1 (1750 -1025)(975 -1025);
FORCEPROP 0 LAST CDS_PHYS_NET_NAME TDR_DIFF_85_BOT_DN
J 0
(1015 -985);
PAINT MONO (1015 -985);
DISPLAY INVISIBLE (1015 -985);
FORCEPROP 2 LAST SIG_NAME TDR_DIFF_85_BOT_DN
J 0
(1090 -1015);
DISPLAY 0.638298 (1090 -1015);
PAINT WHITE (1090 -1015);
WIRE 16 -1 (1750 -875)(975 -875);
FORCEPROP 0 LAST CDS_PHYS_NET_NAME TDR_DIFF_85_BOT_DP
J 0
(1015 -835);
PAINT MONO (1015 -835);
DISPLAY INVISIBLE (1015 -835);
FORCEPROP 2 LAST SIG_NAME TDR_DIFF_85_BOT_DP
J 0
(1090 -865);
DISPLAY 0.638298 (1090 -865);
PAINT WHITE (1090 -865);
WIRE 16 -1 (2425 -875)(2300 -875);
WIRE 16 -1 (2425 -875)(2425 -1025);
WIRE 16 -1 (2300 -1025)(2425 -1025);
WIRE 16 -1 (275 -1025)(425 -1025);
WIRE 16 -1 (275 -875)(275 -1025);
WIRE 16 -1 (275 -875)(425 -875);
WIRE 16 -1 (-2075 1600)(-2775 1600);
WIRE 16 -1 (-2075 1700)(-2775 1700);
FORCEPROP 0 LAST CDS_PHYS_NET_NAME TDR_SE_40_OHM_IN3
J 0
(-2735 1740);
PAINT MONO (-2735 1740);
DISPLAY INVISIBLE (-2735 1740);
FORCEPROP 2 LAST SIG_NAME TDR_SE_40_OHM_IN5
J 0
(-2660 1710);
DISPLAY 0.638298 (-2660 1710);
PAINT WHITE (-2660 1710);
WIRE 16 -1 (-2075 1700)(-2075 1600);
WIRE 16 -1 (2425 2000)(2300 2000);
WIRE 16 -1 (2300 1850)(2425 1850);
WIRE 16 -1 (2425 1850)(2425 2000);
WIRE 16 -1 (2425 1225)(2300 1225);
WIRE 16 -1 (2300 1075)(2425 1075);
WIRE 16 -1 (2425 1075)(2425 1225);
WIRE 16 -1 (2425 -225)(2300 -225);
WIRE 16 -1 (2300 -375)(2425 -375);
WIRE 16 -1 (2425 -375)(2425 -225);
WIRE 16 -1 (1750 -225)(975 -225);
FORCEPROP 0 LAST CDS_PHYS_NET_NAME TDR_DIFF_85_IN4_DP
J 0
(1015 -185);
PAINT MONO (1015 -185);
DISPLAY INVISIBLE (1015 -185);
FORCEPROP 2 LAST SIG_NAME TDR_DIFF_85_IN6_DP
J 0
(1090 -215);
DISPLAY 0.638298 (1090 -215);
PAINT WHITE (1090 -215);
WIRE 16 -1 (1750 -375)(975 -375);
FORCEPROP 0 LAST CDS_PHYS_NET_NAME TDR_DIFF_85_IN4_DN
J 0
(1015 -335);
PAINT MONO (1015 -335);
DISPLAY INVISIBLE (1015 -335);
FORCEPROP 2 LAST SIG_NAME TDR_DIFF_85_IN6_DN
J 0
(1090 -365);
DISPLAY 0.638298 (1090 -365);
PAINT WHITE (1090 -365);
WIRE 16 -1 (2300 400)(2425 400);
WIRE 16 -1 (2425 400)(2425 550);
WIRE 16 -1 (2425 550)(2300 550);
WIRE 16 -1 (1750 2625)(975 2625);
FORCEPROP 0 LAST CDS_PHYS_NET_NAME TDR_DIFF_85_IN2_DN
J 0
(1015 2665);
PAINT MONO (1015 2665);
DISPLAY INVISIBLE (1015 2665);
FORCEPROP 2 LAST SIG_NAME TDR_DIFF_85_IN2_DN
J 0
(1090 2635);
DISPLAY 0.638298 (1090 2635);
PAINT WHITE (1090 2635);
WIRE 16 -1 (4450 4175)(3675 4175);
FORCEPROP 0 LAST CDS_PHYS_NET_NAME TDR_DIFF_100_TOP_DN
J 0
(3715 4215);
PAINT MONO (3715 4215);
DISPLAY INVISIBLE (3715 4215);
FORCEPROP 2 LAST SIG_NAME TDR_DIFF_100_TOP_DN
J 0
(3790 4185);
DISPLAY 0.638298 (3790 4185);
PAINT WHITE (3790 4185);
WIRE 16 -1 (4450 4325)(3675 4325);
FORCEPROP 0 LAST CDS_PHYS_NET_NAME TDR_DIFF_100_TOP_DP
J 0
(3715 4365);
PAINT MONO (3715 4365);
DISPLAY INVISIBLE (3715 4365);
FORCEPROP 2 LAST SIG_NAME TDR_DIFF_100_TOP_DP
J 0
(3790 4335);
DISPLAY 0.638298 (3790 4335);
PAINT WHITE (3790 4335);
WIRE 16 -1 (4450 3400)(3675 3400);
FORCEPROP 0 LAST CDS_PHYS_NET_NAME TDR_DIFF_100_IN1_DN
J 0
(3715 3440);
PAINT MONO (3715 3440);
DISPLAY INVISIBLE (3715 3440);
FORCEPROP 2 LAST SIG_NAME TDR_DIFF_100_IN1_DN
J 0
(3790 3410);
DISPLAY 0.638298 (3790 3410);
PAINT WHITE (3790 3410);
WIRE 16 -1 (4450 3550)(3675 3550);
FORCEPROP 0 LAST CDS_PHYS_NET_NAME TDR_DIFF_100_IN1_DP
J 0
(3715 3590);
PAINT MONO (3715 3590);
DISPLAY INVISIBLE (3715 3590);
FORCEPROP 2 LAST SIG_NAME TDR_DIFF_100_IN1_DP
J 0
(3790 3560);
DISPLAY 0.638298 (3790 3560);
PAINT WHITE (3790 3560);
WIRE 16 -1 (4450 2775)(3675 2775);
FORCEPROP 0 LAST CDS_PHYS_NET_NAME TDR_DIFF_100_IN2_DP
J 0
(3715 2815);
PAINT MONO (3715 2815);
DISPLAY INVISIBLE (3715 2815);
FORCEPROP 2 LAST SIG_NAME TDR_DIFF_100_IN2_DP
J 0
(3790 2785);
DISPLAY 0.638298 (3790 2785);
PAINT WHITE (3790 2785);
WIRE 16 -1 (1750 3400)(975 3400);
FORCEPROP 0 LAST CDS_PHYS_NET_NAME TDR_DIFF_85_IN1_DN
J 0
(1015 3440);
PAINT MONO (1015 3440);
DISPLAY INVISIBLE (1015 3440);
FORCEPROP 2 LAST SIG_NAME TDR_DIFF_85_IN1_DN
J 0
(1090 3410);
DISPLAY 0.638298 (1090 3410);
PAINT WHITE (1090 3410);
WIRE 16 -1 (-1500 4275)(-1350 4275);
WIRE 16 -1 (-1500 2175)(-1350 2175);
WIRE 16 -1 (-1525 1125)(-1375 1125);
WIRE 16 -1 (-1525 1650)(-1375 1650);
WIRE 16 -1 (-3200 4275)(-3050 4275);
WIRE 16 -1 (-3200 3750)(-3050 3750);
WIRE 16 -1 (-3200 3225)(-3050 3225);
WIRE 16 -1 (-3200 2700)(-3050 2700);
WIRE 16 -1 (-3225 1650)(-3075 1650);
WIRE 16 -1 (-3225 1125)(-3075 1125);
WIRE 16 -1 (-1550 575)(-1400 575);
WIRE 16 -1 (-3250 575)(-3100 575);
WIRE 16 -1 (5125 4325)(5000 4325);
WIRE 16 -1 (5000 4175)(5125 4175);
WIRE 16 -1 (5125 4175)(5125 4325);
WIRE 16 -1 (5125 3550)(5000 3550);
WIRE 16 -1 (5000 3400)(5125 3400);
WIRE 16 -1 (5125 3400)(5125 3550);
WIRE 16 -1 (5125 2775)(5000 2775);
WIRE 16 -1 (5000 2625)(5125 2625);
WIRE 16 -1 (5125 2625)(5125 2775);
WIRE 16 -1 (2975 4175)(3125 4175);
WIRE 16 -1 (2975 4175)(2975 4325);
WIRE 16 -1 (2975 4325)(3125 4325);
WIRE 16 -1 (2425 4325)(2300 4325);
WIRE 16 -1 (2300 4175)(2425 4175);
WIRE 16 -1 (2425 4175)(2425 4325);
WIRE 16 -1 (2425 2775)(2300 2775);
WIRE 16 -1 (2300 2625)(2425 2625);
WIRE 16 -1 (2425 2625)(2425 2775);
WIRE 16 -1 (275 4325)(425 4325);
WIRE 16 -1 (275 4175)(425 4175);
WIRE 16 -1 (275 4175)(275 4325);
WIRE 16 -1 (-350 4225)(-1050 4225);
WIRE 16 -1 (-350 4325)(-1050 4325);
FORCEPROP 0 LAST CDS_PHYS_NET_NAME TDR_SE_50_OHM_TOP
J 0
(-1010 4365);
PAINT MONO (-1010 4365);
DISPLAY INVISIBLE (-1010 4365);
FORCEPROP 2 LAST SIG_NAME TDR_SE_50_OHM_TOP
J 0
(-935 4335);
DISPLAY 0.638298 (-935 4335);
PAINT WHITE (-935 4335);
WIRE 16 -1 (-350 4325)(-350 4225);
WIRE 16 -1 (-2050 4225)(-2750 4225);
WIRE 16 -1 (-2050 4325)(-2750 4325);
FORCEPROP 0 LAST CDS_PHYS_NET_NAME TDR_SE_40_OHM_TOP
J 0
(-2710 4365);
PAINT MONO (-2710 4365);
DISPLAY INVISIBLE (-2710 4365);
FORCEPROP 2 LAST SIG_NAME TDR_SE_40_OHM_TOP
J 0
(-2635 4335);
DISPLAY 0.638298 (-2635 4335);
PAINT WHITE (-2635 4335);
WIRE 16 -1 (-2050 4325)(-2050 4225);
WIRE 16 -1 (-2050 3175)(-2750 3175);
WIRE 16 -1 (-2050 3275)(-2750 3275);
FORCEPROP 0 LAST CDS_PHYS_NET_NAME TDR_SE_40_OHM_IN2
J 0
(-2710 3315);
PAINT MONO (-2710 3315);
DISPLAY INVISIBLE (-2710 3315);
FORCEPROP 2 LAST SIG_NAME TDR_SE_40_OHM_IN2
J 0
(-2635 3285);
DISPLAY 0.638298 (-2635 3285);
PAINT WHITE (-2635 3285);
WIRE 16 -1 (-2050 3275)(-2050 3175);
WIRE 16 -1 (-2050 2125)(-2750 2125);
WIRE 16 -1 (-2050 2225)(-2750 2225);
FORCEPROP 0 LAST CDS_PHYS_NET_NAME TDR_SE_40_OHM_IN4
J 0
(-2710 2265);
PAINT MONO (-2710 2265);
DISPLAY INVISIBLE (-2710 2265);
FORCEPROP 2 LAST SIG_NAME TDR_SE_40_OHM_IN4
J 0
(-2635 2235);
DISPLAY 0.638298 (-2635 2235);
PAINT WHITE (-2635 2235);
WIRE 16 -1 (-2050 2225)(-2050 2125);
WIRE 16 -1 (-2100 525)(-2800 525);
WIRE 16 -1 (-2100 625)(-2800 625);
FORCEPROP 0 LAST CDS_PHYS_NET_NAME TDR_SE_40_OHM_BOT
J 0
(-2760 665);
PAINT MONO (-2760 665);
DISPLAY INVISIBLE (-2760 665);
FORCEPROP 2 LAST SIG_NAME TDR_SE_40_OHM_BOT
J 0
(-2685 635);
DISPLAY 0.638298 (-2685 635);
PAINT WHITE (-2685 635);
WIRE 16 -1 (-2100 625)(-2100 525);
DOT 1 (2975 2625);
DOT 1 (2950 -1025);
DOT 1 (5100 -1025);
DOT 1 (5125 1850);
DOT 1 (5125 1075);
DOT 1 (2975 1850);
DOT 1 (2975 1075);
DOT 1 (2950 -375);
DOT 1 (2950 400);
DOT 1 (5100 -375);
DOT 1 (5100 400);
DOT 1 (2425 -1025);
DOT 1 (275 -1025);
DOT 1 (2425 1850);
DOT 1 (2425 1075);
DOT 1 (275 1850);
DOT 1 (275 1075);
DOT 1 (275 -375);
DOT 1 (275 400);
DOT 1 (2425 -375);
DOT 1 (2425 400);
DOT 1 (5125 4175);
DOT 1 (5125 3400);
DOT 1 (5125 2625);
DOT 1 (2975 4175);
DOT 1 (2425 4175);
DOT 1 (2975 3400);
DOT 1 (2425 3400);
DOT 1 (2425 2625);
DOT 1 (275 4175);
DOT 1 (275 3400);
DOT 1 (275 2625);
FORCENOTE
85 OHM
(925 4775) 0;
DISPLAY LEFT (925 4775);
DISPLAY 3.148936 (925 4775);
PAINT WHITE (925 4775);
FORCENOTE
100 OHM
(3525 4775) 0;
DISPLAY LEFT (3525 4775);
DISPLAY 3.148936 (3525 4775);
PAINT WHITE (3525 4775);
FORCENOTE
50 OHM
(-1425 4800) 0;
DISPLAY LEFT (-1425 4800);
DISPLAY 3.148936 (-1425 4800);
PAINT WHITE (-1425 4800);
FORCENOTE
40 OHM
(-3100 4800) 0;
DISPLAY LEFT (-3100 4800);
DISPLAY 3.148936 (-3100 4800);
PAINT WHITE (-3100 4800);
QUIT
